(kicad_sch
	(version 20250114)
	(generator "eeschema")
	(generator_version "9.0")
	(paper "A3")
	(title_block
		(title "SO-DIMM DDR5 Tester")
		(date "2025-11-26")
		(rev "1.3.0")
		(company "Antmicro Ltd.")
		(comment 1 "www.antmicro.com")
		(comment 2 "Antmicro Ltd")
	)
	(text "NOTE: UART RX/TX cross"
		(exclude_from_sim no)
		(at 222.25 207.01 0)
		(effects
			(font
				(size 1.27 1.27)
			)
			(justify left bottom)
		)
	)
	(text "I2C_SCL"
		(exclude_from_sim no)
		(at 162.56 138.43 0)
		(effects
			(font
				(size 1.27 1.27)
			)
			(justify left bottom)
		)
	)
	(text "Debug FTDI"
		(exclude_from_sim no)
		(at 14.605 20.955 0)
		(effects
			(font
				(size 2.9972 2.9972)
				(thickness 0.5994)
				(bold yes)
			)
			(justify left bottom)
		)
	)
	(text "I2C_SDA_IN"
		(exclude_from_sim no)
		(at 162.56 146.05 0)
		(effects
			(font
				(size 1.27 1.27)
			)
			(justify left bottom)
		)
	)
	(text "ICT Testpoints"
		(exclude_from_sim no)
		(at 218.694 250.952 0)
		(effects
			(font
				(size 1.27 1.27)
				(thickness 0.254)
				(bold yes)
			)
			(justify left bottom)
		)
	)
	(text "Note:\nPlace on the bottom side "
		(exclude_from_sim no)
		(at 236.728 251.206 0)
		(effects
			(font
				(size 1.27 1.27)
			)
			(justify left)
		)
	)
	(text "SPI_EN"
		(exclude_from_sim no)
		(at 154.305 148.59 0)
		(effects
			(font
				(size 1.27 1.27)
			)
			(justify left bottom)
		)
	)
	(text "I2C_SDA_OUT"
		(exclude_from_sim no)
		(at 162.56 143.51 0)
		(effects
			(font
				(size 1.27 1.27)
			)
			(justify left bottom)
		)
	)
	(junction
		(at 109.855 132.08)
		(diameter 0)
		(color 0 0 0 0)
	)
	(junction
		(at 59.055 175.26)
		(diameter 0)
		(color 0 0 0 0)
	)
	(junction
		(at 83.82 96.52)
		(diameter 0)
		(color 0 0 0 0)
	)
	(junction
		(at 57.658 158.75)
		(diameter 0)
		(color 0 0 0 0)
	)
	(junction
		(at 108.585 46.99)
		(diameter 0)
		(color 0 0 0 0)
	)
	(junction
		(at 109.855 116.84)
		(diameter 0)
		(color 0 0 0 0)
	)
	(junction
		(at 156.21 223.52)
		(diameter 0)
		(color 0 0 0 0)
	)
	(junction
		(at 82.55 54.61)
		(diameter 0)
		(color 0 0 0 0)
	)
	(junction
		(at 287.02 144.78)
		(diameter 0)
		(color 0 0 0 0)
	)
	(junction
		(at 136.525 46.99)
		(diameter 0)
		(color 0 0 0 0)
	)
	(junction
		(at 102.87 180.34)
		(diameter 0)
		(color 0 0 0 0)
	)
	(junction
		(at 66.802 139.065)
		(diameter 0)
		(color 0 0 0 0)
	)
	(junction
		(at 243.84 148.59)
		(diameter 0)
		(color 0 0 0 0)
	)
	(junction
		(at 56.007 117.475)
		(diameter 0)
		(color 0 0 0 0)
	)
	(junction
		(at 58.547 139.065)
		(diameter 0)
		(color 0 0 0 0)
	)
	(junction
		(at 71.247 117.475)
		(diameter 0)
		(color 0 0 0 0)
	)
	(junction
		(at 109.22 208.28)
		(diameter 0)
		(color 0 0 0 0)
	)
	(junction
		(at 70.485 62.23)
		(diameter 0)
		(color 0 0 0 0)
	)
	(junction
		(at 63.627 117.475)
		(diameter 0)
		(color 0 0 0 0)
	)
	(junction
		(at 243.205 171.45)
		(diameter 0)
		(color 0 0 0 0)
	)
	(junction
		(at 65.532 158.75)
		(diameter 0)
		(color 0 0 0 0)
	)
	(junction
		(at 72.39 87.63)
		(diameter 0)
		(color 0 0 0 0)
	)
	(junction
		(at 243.205 193.04)
		(diameter 0)
		(color 0 0 0 0)
	)
	(junction
		(at 68.58 59.69)
		(diameter 0)
		(color 0 0 0 0)
	)
	(junction
		(at 307.34 129.54)
		(diameter 0)
		(color 0 0 0 0)
	)
	(junction
		(at 68.58 252.095)
		(diameter 0)
		(color 0 0 0 0)
	)
	(junction
		(at 48.387 117.475)
		(diameter 0)
		(color 0 0 0 0)
	)
	(junction
		(at 307.34 138.43)
		(diameter 0)
		(color 0 0 0 0)
	)
	(junction
		(at 133.985 228.6)
		(diameter 0)
		(color 0 0 0 0)
	)
	(junction
		(at 83.82 87.63)
		(diameter 0)
		(color 0 0 0 0)
	)
	(junction
		(at 68.58 239.395)
		(diameter 0)
		(color 0 0 0 0)
	)
	(junction
		(at 268.605 102.235)
		(diameter 0)
		(color 0 0 0 0)
	)
	(junction
		(at 82.55 180.34)
		(diameter 0)
		(color 0 0 0 0)
	)
	(junction
		(at 268.605 135.89)
		(diameter 0)
		(color 0 0 0 0)
	)
	(junction
		(at 51.435 175.26)
		(diameter 0)
		(color 0 0 0 0)
	)
	(junction
		(at 310.515 144.78)
		(diameter 0)
		(color 0 0 0 0)
	)
	(junction
		(at 68.58 245.745)
		(diameter 0)
		(color 0 0 0 0)
	)
	(junction
		(at 147.32 223.52)
		(diameter 0)
		(color 0 0 0 0)
	)
	(junction
		(at 109.22 205.74)
		(diameter 0)
		(color 0 0 0 0)
	)
	(junction
		(at 281.94 102.235)
		(diameter 0)
		(color 0 0 0 0)
	)
	(no_connect
		(at 152.4 170.18)
	)
	(no_connect
		(at 152.4 148.59)
	)
	(no_connect
		(at 152.4 207.01)
	)
	(no_connect
		(at 152.4 153.67)
	)
	(no_connect
		(at 152.4 186.69)
	)
	(no_connect
		(at 121.285 89.535)
	)
	(no_connect
		(at 152.4 127)
	)
	(no_connect
		(at 121.285 81.915)
	)
	(no_connect
		(at 111.76 233.68)
	)
	(no_connect
		(at 262.89 140.97)
	)
	(no_connect
		(at 152.4 165.1)
	)
	(no_connect
		(at 152.4 175.26)
	)
	(no_connect
		(at 152.4 196.85)
	)
	(no_connect
		(at 111.76 231.14)
	)
	(no_connect
		(at 111.76 236.22)
	)
	(no_connect
		(at 152.4 189.23)
	)
	(no_connect
		(at 67.31 72.39)
	)
	(no_connect
		(at 152.4 132.08)
	)
	(no_connect
		(at 152.4 172.72)
	)
	(no_connect
		(at 152.4 199.39)
	)
	(no_connect
		(at 152.4 167.64)
	)
	(no_connect
		(at 152.4 177.8)
	)
	(no_connect
		(at 111.76 228.6)
	)
	(no_connect
		(at 152.4 191.77)
	)
	(no_connect
		(at 152.4 134.62)
	)
	(no_connect
		(at 152.4 194.31)
	)
	(no_connect
		(at 67.31 74.93)
	)
	(no_connect
		(at 111.76 248.92)
	)
	(no_connect
		(at 152.4 156.21)
	)
	(bus_entry
		(at 327.025 198.12)
		(size 2.54 -2.54)
		(stroke
			(width 0)
			(type default)
		)
	)
	(bus_entry
		(at 200.025 138.43)
		(size 2.54 -2.54)
		(stroke
			(width 0)
			(type default)
		)
	)
	(bus_entry
		(at 327.025 176.53)
		(size 2.54 -2.54)
		(stroke
			(width 0)
			(type default)
		)
	)
	(bus_entry
		(at 327.025 144.78)
		(size 2.54 -2.54)
		(stroke
			(width 0)
			(type default)
		)
	)
	(bus_entry
		(at 200.025 140.97)
		(size 2.54 -2.54)
		(stroke
			(width 0)
			(type default)
		)
	)
	(bus_entry
		(at 327.025 138.43)
		(size 2.54 -2.54)
		(stroke
			(width 0)
			(type default)
		)
	)
	(bus_entry
		(at 327.025 173.99)
		(size 2.54 -2.54)
		(stroke
			(width 0)
			(type default)
		)
	)
	(bus_entry
		(at 327.025 112.395)
		(size 2.54 -2.54)
		(stroke
			(width 0)
			(type default)
		)
	)
	(bus_entry
		(at 200.025 143.51)
		(size 2.54 -2.54)
		(stroke
			(width 0)
			(type default)
		)
	)
	(bus_entry
		(at 200.025 151.13)
		(size 2.54 -2.54)
		(stroke
			(width 0)
			(type default)
		)
	)
	(bus_entry
		(at 200.025 146.05)
		(size 2.54 -2.54)
		(stroke
			(width 0)
			(type default)
		)
	)
	(bus_entry
		(at 327.025 114.935)
		(size 2.54 -2.54)
		(stroke
			(width 0)
			(type default)
		)
	)
	(bus_entry
		(at 327.025 107.315)
		(size 2.54 -2.54)
		(stroke
			(width 0)
			(type default)
		)
	)
	(bus_entry
		(at 327.025 109.855)
		(size 2.54 -2.54)
		(stroke
			(width 0)
			(type default)
		)
	)
	(bus_entry
		(at 327.025 195.58)
		(size 2.54 -2.54)
		(stroke
			(width 0)
			(type default)
		)
	)
	(wire
		(pts
			(xy 132.08 241.3) (xy 146.05 241.3)
		)
		(stroke
			(width 0)
			(type default)
		)
	)
	(wire
		(pts
			(xy 361.315 104.775) (xy 361.315 102.235)
		)
		(stroke
			(width 0)
			(type default)
		)
	)
	(wire
		(pts
			(xy 83.82 233.045) (xy 80.645 233.045)
		)
		(stroke
			(width 0)
			(type default)
		)
	)
	(wire
		(pts
			(xy 360.045 186.055) (xy 351.155 186.055)
		)
		(stroke
			(width 0)
			(type default)
		)
	)
	(bus
		(pts
			(xy 202.565 135.89) (xy 202.565 138.43)
		)
		(stroke
			(width 0)
			(type default)
		)
	)
	(wire
		(pts
			(xy 109.855 116.84) (xy 111.76 116.84)
		)
		(stroke
			(width 0)
			(type default)
		)
	)
	(wire
		(pts
			(xy 277.495 198.12) (xy 327.025 198.12)
		)
		(stroke
			(width 0)
			(type default)
		)
	)
	(bus
		(pts
			(xy 329.565 109.855) (xy 329.565 112.395)
		)
		(stroke
			(width 0)
			(type default)
		)
	)
	(wire
		(pts
			(xy 83.82 96.52) (xy 83.82 87.63)
		)
		(stroke
			(width 0)
			(type default)
		)
	)
	(wire
		(pts
			(xy 109.22 205.74) (xy 111.76 205.74)
		)
		(stroke
			(width 0)
			(type default)
		)
	)
	(wire
		(pts
			(xy 371.602 134.62) (xy 371.602 135.89)
		)
		(stroke
			(width 0)
			(type default)
		)
	)
	(wire
		(pts
			(xy 72.39 96.52) (xy 72.39 87.63)
		)
		(stroke
			(width 0)
			(type default)
		)
	)
	(wire
		(pts
			(xy 56.007 117.475) (xy 63.627 117.475)
		)
		(stroke
			(width 0)
			(type default)
		)
	)
	(wire
		(pts
			(xy 277.495 195.58) (xy 327.025 195.58)
		)
		(stroke
			(width 0)
			(type default)
		)
	)
	(wire
		(pts
			(xy 83.82 238.76) (xy 83.82 233.045)
		)
		(stroke
			(width 0)
			(type default)
		)
	)
	(wire
		(pts
			(xy 262.89 171.45) (xy 265.43 171.45)
		)
		(stroke
			(width 0)
			(type default)
		)
	)
	(wire
		(pts
			(xy 262.89 114.935) (xy 272.415 114.935)
		)
		(stroke
			(width 0)
			(type default)
		)
	)
	(wire
		(pts
			(xy 66.802 138.43) (xy 66.802 139.065)
		)
		(stroke
			(width 0)
			(type default)
		)
	)
	(wire
		(pts
			(xy 372.11 168.91) (xy 372.11 166.37)
		)
		(stroke
			(width 0)
			(type default)
		)
	)
	(wire
		(pts
			(xy 361.315 109.855) (xy 361.315 111.125)
		)
		(stroke
			(width 0)
			(type default)
		)
	)
	(bus
		(pts
			(xy 330.2 102.87) (xy 329.565 103.505)
		)
		(stroke
			(width 0)
			(type default)
		)
	)
	(wire
		(pts
			(xy 243.84 148.59) (xy 243.84 149.86)
		)
		(stroke
			(width 0)
			(type default)
		)
	)
	(wire
		(pts
			(xy 265.43 133.35) (xy 265.43 128.905)
		)
		(stroke
			(width 0)
			(type default)
		)
	)
	(wire
		(pts
			(xy 277.495 114.935) (xy 327.025 114.935)
		)
		(stroke
			(width 0)
			(type default)
		)
	)
	(wire
		(pts
			(xy 223.52 193.04) (xy 243.205 193.04)
		)
		(stroke
			(width 0)
			(type default)
		)
	)
	(wire
		(pts
			(xy 229.87 114.935) (xy 245.11 114.935)
		)
		(stroke
			(width 0)
			(type default)
		)
	)
	(wire
		(pts
			(xy 68.58 239.395) (xy 73.025 239.395)
		)
		(stroke
			(width 0)
			(type default)
		)
	)
	(wire
		(pts
			(xy 136.525 46.99) (xy 146.685 46.99)
		)
		(stroke
			(width 0)
			(type default)
		)
	)
	(wire
		(pts
			(xy 360.045 173.99) (xy 360.045 175.26)
		)
		(stroke
			(width 0)
			(type default)
		)
	)
	(wire
		(pts
			(xy 39.497 117.475) (xy 48.387 117.475)
		)
		(stroke
			(width 0)
			(type default)
		)
	)
	(wire
		(pts
			(xy 287.02 144.78) (xy 290.83 144.78)
		)
		(stroke
			(width 0)
			(type default)
		)
	)
	(wire
		(pts
			(xy 245.11 274.32) (xy 245.11 275.59)
		)
		(stroke
			(width 0)
			(type default)
		)
	)
	(wire
		(pts
			(xy 277.495 176.53) (xy 327.025 176.53)
		)
		(stroke
			(width 0)
			(type default)
		)
	)
	(wire
		(pts
			(xy 152.4 160.02) (xy 175.26 160.02)
		)
		(stroke
			(width 0)
			(type default)
		)
	)
	(wire
		(pts
			(xy 96.52 132.08) (xy 109.855 132.08)
		)
		(stroke
			(width 0)
			(type default)
		)
	)
	(wire
		(pts
			(xy 82.55 54.61) (xy 85.725 54.61)
		)
		(stroke
			(width 0)
			(type default)
		)
	)
	(wire
		(pts
			(xy 82.55 171.45) (xy 82.55 180.34)
		)
		(stroke
			(width 0)
			(type default)
		)
	)
	(wire
		(pts
			(xy 372.11 173.99) (xy 372.11 175.26)
		)
		(stroke
			(width 0)
			(type default)
		)
	)
	(wire
		(pts
			(xy 277.495 109.855) (xy 327.025 109.855)
		)
		(stroke
			(width 0)
			(type default)
		)
	)
	(wire
		(pts
			(xy 109.855 49.53) (xy 108.585 49.53)
		)
		(stroke
			(width 0)
			(type default)
		)
	)
	(wire
		(pts
			(xy 68.58 59.69) (xy 81.915 59.69)
		)
		(stroke
			(width 0)
			(type default)
		)
	)
	(wire
		(pts
			(xy 268.605 97.79) (xy 268.605 102.235)
		)
		(stroke
			(width 0)
			(type default)
		)
	)
	(wire
		(pts
			(xy 82.55 171.45) (xy 111.76 171.45)
		)
		(stroke
			(width 0)
			(type default)
		)
	)
	(wire
		(pts
			(xy 232.41 266.7) (xy 232.41 275.59)
		)
		(stroke
			(width 0)
			(type default)
		)
	)
	(wire
		(pts
			(xy 72.39 87.63) (xy 75.565 87.63)
		)
		(stroke
			(width 0)
			(type default)
		)
	)
	(wire
		(pts
			(xy 262.89 200.66) (xy 264.16 200.66)
		)
		(stroke
			(width 0)
			(type default)
		)
	)
	(wire
		(pts
			(xy 229.362 133.35) (xy 245.11 133.35)
		)
		(stroke
			(width 0)
			(type default)
		)
	)
	(wire
		(pts
			(xy 95.25 241.3) (xy 111.76 241.3)
		)
		(stroke
			(width 0)
			(type default)
		)
	)
	(wire
		(pts
			(xy 121.285 92.075) (xy 122.555 92.075)
		)
		(stroke
			(width 0)
			(type default)
		)
	)
	(wire
		(pts
			(xy 83.82 80.01) (xy 83.82 87.63)
		)
		(stroke
			(width 0)
			(type default)
		)
	)
	(wire
		(pts
			(xy 262.89 173.99) (xy 272.415 173.99)
		)
		(stroke
			(width 0)
			(type default)
		)
	)
	(wire
		(pts
			(xy 156.21 223.52) (xy 165.735 223.52)
		)
		(stroke
			(width 0)
			(type default)
		)
	)
	(wire
		(pts
			(xy 65.532 158.115) (xy 65.532 158.75)
		)
		(stroke
			(width 0)
			(type default)
		)
	)
	(wire
		(pts
			(xy 68.58 59.69) (xy 68.58 64.77)
		)
		(stroke
			(width 0)
			(type default)
		)
	)
	(wire
		(pts
			(xy 133.985 228.6) (xy 133.985 236.22)
		)
		(stroke
			(width 0)
			(type default)
		)
	)
	(wire
		(pts
			(xy 56.388 139.065) (xy 58.547 139.065)
		)
		(stroke
			(width 0)
			(type default)
		)
	)
	(wire
		(pts
			(xy 67.31 59.69) (xy 68.58 59.69)
		)
		(stroke
			(width 0)
			(type default)
		)
	)
	(wire
		(pts
			(xy 238.76 266.7) (xy 238.76 275.59)
		)
		(stroke
			(width 0)
			(type default)
		)
	)
	(bus
		(pts
			(xy 202.565 134.62) (xy 202.565 135.89)
		)
		(stroke
			(width 0)
			(type default)
		)
	)
	(wire
		(pts
			(xy 243.84 118.745) (xy 243.84 117.475)
		)
		(stroke
			(width 0)
			(type default)
		)
	)
	(wire
		(pts
			(xy 63.627 117.475) (xy 71.247 117.475)
		)
		(stroke
			(width 0)
			(type default)
		)
	)
	(wire
		(pts
			(xy 262.89 109.855) (xy 272.415 109.855)
		)
		(stroke
			(width 0)
			(type default)
		)
	)
	(wire
		(pts
			(xy 245.11 140.97) (xy 243.84 140.97)
		)
		(stroke
			(width 0)
			(type default)
		)
	)
	(wire
		(pts
			(xy 71.247 117.475) (xy 71.247 120.015)
		)
		(stroke
			(width 0)
			(type default)
		)
	)
	(wire
		(pts
			(xy 152.4 119.38) (xy 173.355 119.38)
		)
		(stroke
			(width 0)
			(type default)
		)
	)
	(wire
		(pts
			(xy 268.605 102.235) (xy 272.415 102.235)
		)
		(stroke
			(width 0)
			(type default)
		)
	)
	(wire
		(pts
			(xy 251.46 273.05) (xy 251.46 276.86)
		)
		(stroke
			(width 0)
			(type default)
		)
	)
	(wire
		(pts
			(xy 229.87 107.315) (xy 245.11 107.315)
		)
		(stroke
			(width 0)
			(type default)
		)
	)
	(wire
		(pts
			(xy 136.525 44.45) (xy 136.525 46.99)
		)
		(stroke
			(width 0)
			(type default)
		)
	)
	(wire
		(pts
			(xy 152.4 143.51) (xy 179.705 143.51)
		)
		(stroke
			(width 0)
			(type default)
		)
	)
	(wire
		(pts
			(xy 102.87 180.34) (xy 102.87 181.61)
		)
		(stroke
			(width 0)
			(type default)
		)
	)
	(wire
		(pts
			(xy 262.89 146.05) (xy 287.02 146.05)
		)
		(stroke
			(width 0)
			(type default)
		)
	)
	(wire
		(pts
			(xy 372.237 110.49) (xy 372.237 111.76)
		)
		(stroke
			(width 0)
			(type default)
		)
	)
	(wire
		(pts
			(xy 229.87 112.395) (xy 245.11 112.395)
		)
		(stroke
			(width 0)
			(type default)
		)
	)
	(wire
		(pts
			(xy 262.89 198.12) (xy 272.415 198.12)
		)
		(stroke
			(width 0)
			(type default)
		)
	)
	(wire
		(pts
			(xy 229.362 146.05) (xy 245.11 146.05)
		)
		(stroke
			(width 0)
			(type default)
		)
	)
	(wire
		(pts
			(xy 96.52 129.54) (xy 111.76 129.54)
		)
		(stroke
			(width 0)
			(type default)
		)
	)
	(wire
		(pts
			(xy 95.25 243.84) (xy 111.76 243.84)
		)
		(stroke
			(width 0)
			(type default)
		)
	)
	(bus
		(pts
			(xy 203.2 133.985) (xy 202.565 134.62)
		)
		(stroke
			(width 0)
			(type default)
		)
	)
	(wire
		(pts
			(xy 83.185 243.84) (xy 83.185 245.745)
		)
		(stroke
			(width 0)
			(type default)
		)
	)
	(wire
		(pts
			(xy 229.362 138.43) (xy 245.11 138.43)
		)
		(stroke
			(width 0)
			(type default)
		)
	)
	(wire
		(pts
			(xy 95.25 246.38) (xy 111.76 246.38)
		)
		(stroke
			(width 0)
			(type default)
		)
	)
	(wire
		(pts
			(xy 264.16 266.7) (xy 264.16 275.59)
		)
		(stroke
			(width 0)
			(type default)
		)
	)
	(bus
		(pts
			(xy 329.565 193.04) (xy 329.565 195.58)
		)
		(stroke
			(width 0)
			(type default)
		)
	)
	(wire
		(pts
			(xy 141.605 223.52) (xy 147.32 223.52)
		)
		(stroke
			(width 0)
			(type default)
		)
	)
	(wire
		(pts
			(xy 109.22 194.31) (xy 111.76 194.31)
		)
		(stroke
			(width 0)
			(type default)
		)
	)
	(wire
		(pts
			(xy 68.58 252.095) (xy 68.58 254.635)
		)
		(stroke
			(width 0)
			(type default)
		)
	)
	(wire
		(pts
			(xy 288.29 266.7) (xy 288.29 275.59)
		)
		(stroke
			(width 0)
			(type default)
		)
	)
	(wire
		(pts
			(xy 243.205 200.66) (xy 243.205 193.04)
		)
		(stroke
			(width 0)
			(type default)
		)
	)
	(wire
		(pts
			(xy 307.34 127.635) (xy 307.34 129.54)
		)
		(stroke
			(width 0)
			(type default)
		)
	)
	(wire
		(pts
			(xy 65.532 161.29) (xy 65.532 158.75)
		)
		(stroke
			(width 0)
			(type default)
		)
	)
	(wire
		(pts
			(xy 223.52 173.99) (xy 245.11 173.99)
		)
		(stroke
			(width 0)
			(type default)
		)
	)
	(bus
		(pts
			(xy 202.565 140.97) (xy 202.565 143.51)
		)
		(stroke
			(width 0)
			(type default)
		)
	)
	(bus
		(pts
			(xy 332.105 191.135) (xy 330.2 191.135)
		)
		(stroke
			(width 0)
			(type default)
		)
	)
	(wire
		(pts
			(xy 95.25 238.76) (xy 111.76 238.76)
		)
		(stroke
			(width 0)
			(type default)
		)
	)
	(wire
		(pts
			(xy 108.585 46.99) (xy 109.855 46.99)
		)
		(stroke
			(width 0)
			(type default)
		)
	)
	(wire
		(pts
			(xy 73.025 233.045) (xy 68.58 233.045)
		)
		(stroke
			(width 0)
			(type default)
		)
	)
	(wire
		(pts
			(xy 66.802 139.065) (xy 77.597 139.065)
		)
		(stroke
			(width 0)
			(type default)
		)
	)
	(wire
		(pts
			(xy 276.86 266.7) (xy 276.86 275.59)
		)
		(stroke
			(width 0)
			(type default)
		)
	)
	(wire
		(pts
			(xy 66.802 139.065) (xy 66.802 140.97)
		)
		(stroke
			(width 0)
			(type default)
		)
	)
	(wire
		(pts
			(xy 96.52 163.83) (xy 111.76 163.83)
		)
		(stroke
			(width 0)
			(type default)
		)
	)
	(wire
		(pts
			(xy 97.155 180.34) (xy 102.87 180.34)
		)
		(stroke
			(width 0)
			(type default)
		)
	)
	(wire
		(pts
			(xy 82.55 180.34) (xy 82.55 181.61)
		)
		(stroke
			(width 0)
			(type default)
		)
	)
	(wire
		(pts
			(xy 141.605 228.6) (xy 141.605 223.52)
		)
		(stroke
			(width 0)
			(type default)
		)
	)
	(wire
		(pts
			(xy 68.58 233.045) (xy 68.58 239.395)
		)
		(stroke
			(width 0)
			(type default)
		)
	)
	(wire
		(pts
			(xy 243.205 171.45) (xy 245.11 171.45)
		)
		(stroke
			(width 0)
			(type default)
		)
	)
	(wire
		(pts
			(xy 307.34 129.54) (xy 310.515 129.54)
		)
		(stroke
			(width 0)
			(type default)
		)
	)
	(wire
		(pts
			(xy 51.435 175.26) (xy 51.435 177.8)
		)
		(stroke
			(width 0)
			(type default)
		)
	)
	(wire
		(pts
			(xy 72.39 52.07) (xy 67.31 52.07)
		)
		(stroke
			(width 0)
			(type default)
		)
	)
	(wire
		(pts
			(xy 82.55 52.07) (xy 82.55 54.61)
		)
		(stroke
			(width 0)
			(type default)
		)
	)
	(wire
		(pts
			(xy 77.47 52.07) (xy 82.55 52.07)
		)
		(stroke
			(width 0)
			(type default)
		)
	)
	(wire
		(pts
			(xy 295.91 138.43) (xy 307.34 138.43)
		)
		(stroke
			(width 0)
			(type default)
		)
	)
	(wire
		(pts
			(xy 156.21 226.06) (xy 156.21 223.52)
		)
		(stroke
			(width 0)
			(type default)
		)
	)
	(wire
		(pts
			(xy 109.22 205.74) (xy 109.22 208.28)
		)
		(stroke
			(width 0)
			(type default)
		)
	)
	(bus
		(pts
			(xy 329.565 104.775) (xy 329.565 107.315)
		)
		(stroke
			(width 0)
			(type default)
		)
	)
	(wire
		(pts
			(xy 89.535 180.34) (xy 82.55 180.34)
		)
		(stroke
			(width 0)
			(type default)
		)
	)
	(wire
		(pts
			(xy 184.785 143.51) (xy 200.025 143.51)
		)
		(stroke
			(width 0)
			(type default)
		)
	)
	(wire
		(pts
			(xy 109.22 194.31) (xy 109.22 197.485)
		)
		(stroke
			(width 0)
			(type default)
		)
	)
	(wire
		(pts
			(xy 65.532 158.75) (xy 76.073 158.75)
		)
		(stroke
			(width 0)
			(type default)
		)
	)
	(wire
		(pts
			(xy 72.39 82.55) (xy 67.31 82.55)
		)
		(stroke
			(width 0)
			(type default)
		)
	)
	(wire
		(pts
			(xy 307.34 138.43) (xy 327.025 138.43)
		)
		(stroke
			(width 0)
			(type default)
		)
	)
	(wire
		(pts
			(xy 67.31 46.99) (xy 77.47 46.99)
		)
		(stroke
			(width 0)
			(type default)
		)
	)
	(wire
		(pts
			(xy 268.605 135.89) (xy 276.225 135.89)
		)
		(stroke
			(width 0)
			(type default)
		)
	)
	(wire
		(pts
			(xy 80.645 245.745) (xy 83.185 245.745)
		)
		(stroke
			(width 0)
			(type default)
		)
	)
	(wire
		(pts
			(xy 226.06 266.7) (xy 226.06 275.59)
		)
		(stroke
			(width 0)
			(type default)
		)
	)
	(wire
		(pts
			(xy 109.855 123.19) (xy 111.76 123.19)
		)
		(stroke
			(width 0)
			(type default)
		)
	)
	(wire
		(pts
			(xy 56.007 117.475) (xy 56.007 120.015)
		)
		(stroke
			(width 0)
			(type default)
		)
	)
	(wire
		(pts
			(xy 132.08 238.76) (xy 146.05 238.76)
		)
		(stroke
			(width 0)
			(type default)
		)
	)
	(wire
		(pts
			(xy 75.565 96.52) (xy 72.39 96.52)
		)
		(stroke
			(width 0)
			(type default)
		)
	)
	(wire
		(pts
			(xy 96.52 116.84) (xy 109.855 116.84)
		)
		(stroke
			(width 0)
			(type default)
		)
	)
	(wire
		(pts
			(xy 223.52 171.45) (xy 243.205 171.45)
		)
		(stroke
			(width 0)
			(type default)
		)
	)
	(wire
		(pts
			(xy 130.175 46.99) (xy 136.525 46.99)
		)
		(stroke
			(width 0)
			(type default)
		)
	)
	(wire
		(pts
			(xy 229.87 109.855) (xy 245.11 109.855)
		)
		(stroke
			(width 0)
			(type default)
		)
	)
	(wire
		(pts
			(xy 152.4 138.43) (xy 179.705 138.43)
		)
		(stroke
			(width 0)
			(type default)
		)
	)
	(wire
		(pts
			(xy 184.785 140.97) (xy 200.025 140.97)
		)
		(stroke
			(width 0)
			(type default)
		)
	)
	(wire
		(pts
			(xy 55.753 158.75) (xy 57.658 158.75)
		)
		(stroke
			(width 0)
			(type default)
		)
	)
	(bus
		(pts
			(xy 329.565 191.77) (xy 329.565 193.04)
		)
		(stroke
			(width 0)
			(type default)
		)
	)
	(bus
		(pts
			(xy 332.105 169.545) (xy 330.2 169.545)
		)
		(stroke
			(width 0)
			(type default)
		)
	)
	(wire
		(pts
			(xy 265.43 193.04) (xy 265.43 191.135)
		)
		(stroke
			(width 0)
			(type default)
		)
	)
	(wire
		(pts
			(xy 147.32 231.14) (xy 147.32 233.68)
		)
		(stroke
			(width 0)
			(type default)
		)
	)
	(wire
		(pts
			(xy 101.6 57.15) (xy 101.6 54.61)
		)
		(stroke
			(width 0)
			(type default)
		)
	)
	(wire
		(pts
			(xy 360.045 166.37) (xy 351.155 166.37)
		)
		(stroke
			(width 0)
			(type default)
		)
	)
	(wire
		(pts
			(xy 262.89 138.43) (xy 290.83 138.43)
		)
		(stroke
			(width 0)
			(type default)
		)
	)
	(wire
		(pts
			(xy 372.237 105.41) (xy 372.237 102.87)
		)
		(stroke
			(width 0)
			(type default)
		)
	)
	(wire
		(pts
			(xy 243.205 193.04) (xy 245.11 193.04)
		)
		(stroke
			(width 0)
			(type default)
		)
	)
	(wire
		(pts
			(xy 96.52 127) (xy 111.76 127)
		)
		(stroke
			(width 0)
			(type default)
		)
	)
	(wire
		(pts
			(xy 101.6 46.99) (xy 108.585 46.99)
		)
		(stroke
			(width 0)
			(type default)
		)
	)
	(wire
		(pts
			(xy 110.49 153.67) (xy 111.76 153.67)
		)
		(stroke
			(width 0)
			(type default)
		)
	)
	(wire
		(pts
			(xy 65.532 167.64) (xy 65.532 166.37)
		)
		(stroke
			(width 0)
			(type default)
		)
	)
	(wire
		(pts
			(xy 164.465 204.47) (xy 152.4 204.47)
		)
		(stroke
			(width 0)
			(type default)
		)
	)
	(wire
		(pts
			(xy 71.247 116.84) (xy 71.247 117.475)
		)
		(stroke
			(width 0)
			(type default)
		)
	)
	(bus
		(pts
			(xy 202.565 138.43) (xy 202.565 140.97)
		)
		(stroke
			(width 0)
			(type default)
		)
	)
	(wire
		(pts
			(xy 82.55 54.61) (xy 77.47 54.61)
		)
		(stroke
			(width 0)
			(type default)
		)
	)
	(wire
		(pts
			(xy 147.32 223.52) (xy 147.32 226.06)
		)
		(stroke
			(width 0)
			(type default)
		)
	)
	(wire
		(pts
			(xy 223.52 195.58) (xy 245.11 195.58)
		)
		(stroke
			(width 0)
			(type default)
		)
	)
	(wire
		(pts
			(xy 132.08 228.6) (xy 133.985 228.6)
		)
		(stroke
			(width 0)
			(type default)
		)
	)
	(wire
		(pts
			(xy 72.39 54.61) (xy 67.31 54.61)
		)
		(stroke
			(width 0)
			(type default)
		)
	)
	(wire
		(pts
			(xy 219.71 266.7) (xy 219.71 275.59)
		)
		(stroke
			(width 0)
			(type default)
		)
	)
	(bus
		(pts
			(xy 329.565 135.89) (xy 329.565 142.24)
		)
		(stroke
			(width 0)
			(type default)
		)
	)
	(wire
		(pts
			(xy 83.82 96.52) (xy 83.82 97.79)
		)
		(stroke
			(width 0)
			(type default)
		)
	)
	(wire
		(pts
			(xy 359.41 129.54) (xy 359.41 127)
		)
		(stroke
			(width 0)
			(type default)
		)
	)
	(wire
		(pts
			(xy 80.645 96.52) (xy 83.82 96.52)
		)
		(stroke
			(width 0)
			(type default)
		)
	)
	(wire
		(pts
			(xy 132.08 243.84) (xy 146.05 243.84)
		)
		(stroke
			(width 0)
			(type default)
		)
	)
	(wire
		(pts
			(xy 287.02 144.78) (xy 287.02 143.51)
		)
		(stroke
			(width 0)
			(type default)
		)
	)
	(wire
		(pts
			(xy 372.11 193.675) (xy 372.11 194.945)
		)
		(stroke
			(width 0)
			(type default)
		)
	)
	(wire
		(pts
			(xy 96.52 139.7) (xy 111.76 139.7)
		)
		(stroke
			(width 0)
			(type default)
		)
	)
	(wire
		(pts
			(xy 262.89 176.53) (xy 272.415 176.53)
		)
		(stroke
			(width 0)
			(type default)
		)
	)
	(wire
		(pts
			(xy 310.515 144.78) (xy 327.025 144.78)
		)
		(stroke
			(width 0)
			(type default)
		)
	)
	(wire
		(pts
			(xy 67.31 67.31) (xy 70.485 67.31)
		)
		(stroke
			(width 0)
			(type default)
		)
	)
	(wire
		(pts
			(xy 96.52 153.67) (xy 105.41 153.67)
		)
		(stroke
			(width 0)
			(type default)
		)
	)
	(wire
		(pts
			(xy 294.64 266.7) (xy 294.64 275.59)
		)
		(stroke
			(width 0)
			(type default)
		)
	)
	(wire
		(pts
			(xy 70.485 67.31) (xy 70.485 62.23)
		)
		(stroke
			(width 0)
			(type default)
		)
	)
	(wire
		(pts
			(xy 152.4 116.84) (xy 173.355 116.84)
		)
		(stroke
			(width 0)
			(type default)
		)
	)
	(wire
		(pts
			(xy 229.87 102.235) (xy 245.11 102.235)
		)
		(stroke
			(width 0)
			(type default)
		)
	)
	(bus
		(pts
			(xy 329.565 134.62) (xy 329.565 135.89)
		)
		(stroke
			(width 0)
			(type default)
		)
	)
	(wire
		(pts
			(xy 132.715 86.995) (xy 121.285 86.995)
		)
		(stroke
			(width 0)
			(type default)
		)
	)
	(bus
		(pts
			(xy 332.105 133.985) (xy 330.2 133.985)
		)
		(stroke
			(width 0)
			(type default)
		)
	)
	(wire
		(pts
			(xy 245.11 179.07) (xy 243.205 179.07)
		)
		(stroke
			(width 0)
			(type default)
		)
	)
	(wire
		(pts
			(xy 132.08 233.68) (xy 147.32 233.68)
		)
		(stroke
			(width 0)
			(type default)
		)
	)
	(wire
		(pts
			(xy 80.645 239.395) (xy 83.185 239.395)
		)
		(stroke
			(width 0)
			(type default)
		)
	)
	(wire
		(pts
			(xy 83.82 252.095) (xy 80.645 252.095)
		)
		(stroke
			(width 0)
			(type default)
		)
	)
	(wire
		(pts
			(xy 262.89 195.58) (xy 272.415 195.58)
		)
		(stroke
			(width 0)
			(type default)
		)
	)
	(wire
		(pts
			(xy 281.94 102.235) (xy 281.94 104.775)
		)
		(stroke
			(width 0)
			(type default)
		)
	)
	(wire
		(pts
			(xy 152.4 129.54) (xy 172.72 129.54)
		)
		(stroke
			(width 0)
			(type default)
		)
	)
	(bus
		(pts
			(xy 329.565 171.45) (xy 329.565 173.99)
		)
		(stroke
			(width 0)
			(type default)
		)
	)
	(wire
		(pts
			(xy 262.89 112.395) (xy 272.415 112.395)
		)
		(stroke
			(width 0)
			(type default)
		)
	)
	(wire
		(pts
			(xy 102.87 176.53) (xy 111.76 176.53)
		)
		(stroke
			(width 0)
			(type default)
		)
	)
	(wire
		(pts
			(xy 136.525 57.15) (xy 136.525 54.61)
		)
		(stroke
			(width 0)
			(type default)
		)
	)
	(wire
		(pts
			(xy 48.387 117.475) (xy 56.007 117.475)
		)
		(stroke
			(width 0)
			(type default)
		)
	)
	(wire
		(pts
			(xy 131.445 49.53) (xy 131.445 57.15)
		)
		(stroke
			(width 0)
			(type default)
		)
	)
	(wire
		(pts
			(xy 66.675 175.26) (xy 66.675 177.8)
		)
		(stroke
			(width 0)
			(type default)
		)
	)
	(wire
		(pts
			(xy 109.855 132.08) (xy 109.855 123.19)
		)
		(stroke
			(width 0)
			(type default)
		)
	)
	(wire
		(pts
			(xy 72.39 82.55) (xy 72.39 87.63)
		)
		(stroke
			(width 0)
			(type default)
		)
	)
	(wire
		(pts
			(xy 281.305 133.35) (xy 298.45 133.35)
		)
		(stroke
			(width 0)
			(type default)
		)
	)
	(wire
		(pts
			(xy 152.4 121.92) (xy 173.355 121.92)
		)
		(stroke
			(width 0)
			(type default)
		)
	)
	(wire
		(pts
			(xy 262.89 133.35) (xy 265.43 133.35)
		)
		(stroke
			(width 0)
			(type default)
		)
	)
	(wire
		(pts
			(xy 39.497 175.26) (xy 51.435 175.26)
		)
		(stroke
			(width 0)
			(type default)
		)
	)
	(wire
		(pts
			(xy 132.715 84.455) (xy 121.285 84.455)
		)
		(stroke
			(width 0)
			(type default)
		)
	)
	(wire
		(pts
			(xy 39.497 158.75) (xy 50.673 158.75)
		)
		(stroke
			(width 0)
			(type default)
		)
	)
	(wire
		(pts
			(xy 277.495 112.395) (xy 327.025 112.395)
		)
		(stroke
			(width 0)
			(type default)
		)
	)
	(wire
		(pts
			(xy 152.4 184.15) (xy 175.26 184.15)
		)
		(stroke
			(width 0)
			(type default)
		)
	)
	(wire
		(pts
			(xy 265.43 171.45) (xy 265.43 167.005)
		)
		(stroke
			(width 0)
			(type default)
		)
	)
	(wire
		(pts
			(xy 262.89 193.04) (xy 265.43 193.04)
		)
		(stroke
			(width 0)
			(type default)
		)
	)
	(wire
		(pts
			(xy 66.802 147.32) (xy 66.802 146.05)
		)
		(stroke
			(width 0)
			(type default)
		)
	)
	(wire
		(pts
			(xy 57.658 167.64) (xy 57.658 166.37)
		)
		(stroke
			(width 0)
			(type default)
		)
	)
	(wire
		(pts
			(xy 243.205 179.07) (xy 243.205 171.45)
		)
		(stroke
			(width 0)
			(type default)
		)
	)
	(wire
		(pts
			(xy 360.045 193.675) (xy 360.045 194.945)
		)
		(stroke
			(width 0)
			(type default)
		)
	)
	(wire
		(pts
			(xy 262.89 107.315) (xy 272.415 107.315)
		)
		(stroke
			(width 0)
			(type default)
		)
	)
	(wire
		(pts
			(xy 109.855 132.08) (xy 111.76 132.08)
		)
		(stroke
			(width 0)
			(type default)
		)
	)
	(wire
		(pts
			(xy 262.89 102.235) (xy 268.605 102.235)
		)
		(stroke
			(width 0)
			(type default)
		)
	)
	(wire
		(pts
			(xy 58.547 147.32) (xy 58.547 146.05)
		)
		(stroke
			(width 0)
			(type default)
		)
	)
	(wire
		(pts
			(xy 245.11 200.66) (xy 243.205 200.66)
		)
		(stroke
			(width 0)
			(type default)
		)
	)
	(wire
		(pts
			(xy 83.185 241.3) (xy 90.17 241.3)
		)
		(stroke
			(width 0)
			(type default)
		)
	)
	(wire
		(pts
			(xy 243.84 117.475) (xy 245.11 117.475)
		)
		(stroke
			(width 0)
			(type default)
		)
	)
	(wire
		(pts
			(xy 96.52 142.24) (xy 111.76 142.24)
		)
		(stroke
			(width 0)
			(type default)
		)
	)
	(wire
		(pts
			(xy 184.785 151.13) (xy 200.025 151.13)
		)
		(stroke
			(width 0)
			(type default)
		)
	)
	(bus
		(pts
			(xy 202.565 143.51) (xy 202.565 148.59)
		)
		(stroke
			(width 0)
			(type default)
		)
	)
	(wire
		(pts
			(xy 130.175 49.53) (xy 131.445 49.53)
		)
		(stroke
			(width 0)
			(type default)
		)
	)
	(wire
		(pts
			(xy 277.495 102.235) (xy 281.94 102.235)
		)
		(stroke
			(width 0)
			(type default)
		)
	)
	(wire
		(pts
			(xy 102.87 176.53) (xy 102.87 180.34)
		)
		(stroke
			(width 0)
			(type default)
		)
	)
	(wire
		(pts
			(xy 223.52 176.53) (xy 245.11 176.53)
		)
		(stroke
			(width 0)
			(type default)
		)
	)
	(wire
		(pts
			(xy 156.21 223.52) (xy 147.32 223.52)
		)
		(stroke
			(width 0)
			(type default)
		)
	)
	(wire
		(pts
			(xy 281.94 273.05) (xy 281.94 276.86)
		)
		(stroke
			(width 0)
			(type default)
		)
	)
	(wire
		(pts
			(xy 359.41 134.62) (xy 359.41 135.89)
		)
		(stroke
			(width 0)
			(type default)
		)
	)
	(wire
		(pts
			(xy 108.585 46.99) (xy 108.585 49.53)
		)
		(stroke
			(width 0)
			(type default)
		)
	)
	(wire
		(pts
			(xy 109.22 202.565) (xy 109.22 205.74)
		)
		(stroke
			(width 0)
			(type default)
		)
	)
	(wire
		(pts
			(xy 57.658 158.75) (xy 65.532 158.75)
		)
		(stroke
			(width 0)
			(type default)
		)
	)
	(wire
		(pts
			(xy 360.045 168.91) (xy 360.045 166.37)
		)
		(stroke
			(width 0)
			(type default)
		)
	)
	(wire
		(pts
			(xy 284.48 143.51) (xy 287.02 143.51)
		)
		(stroke
			(width 0)
			(type default)
		)
	)
	(wire
		(pts
			(xy 68.58 239.395) (xy 68.58 245.745)
		)
		(stroke
			(width 0)
			(type default)
		)
	)
	(wire
		(pts
			(xy 257.81 266.7) (xy 257.81 275.59)
		)
		(stroke
			(width 0)
			(type default)
		)
	)
	(wire
		(pts
			(xy 132.08 248.92) (xy 133.35 248.92)
		)
		(stroke
			(width 0)
			(type default)
		)
	)
	(wire
		(pts
			(xy 96.52 161.29) (xy 111.76 161.29)
		)
		(stroke
			(width 0)
			(type default)
		)
	)
	(wire
		(pts
			(xy 277.495 173.99) (xy 327.025 173.99)
		)
		(stroke
			(width 0)
			(type default)
		)
	)
	(wire
		(pts
			(xy 152.4 140.97) (xy 179.705 140.97)
		)
		(stroke
			(width 0)
			(type default)
		)
	)
	(wire
		(pts
			(xy 361.315 102.235) (xy 352.425 102.235)
		)
		(stroke
			(width 0)
			(type default)
		)
	)
	(wire
		(pts
			(xy 51.435 175.26) (xy 59.055 175.26)
		)
		(stroke
			(width 0)
			(type default)
		)
	)
	(wire
		(pts
			(xy 270.51 266.7) (xy 270.51 275.59)
		)
		(stroke
			(width 0)
			(type default)
		)
	)
	(wire
		(pts
			(xy 276.225 133.35) (xy 268.605 133.35)
		)
		(stroke
			(width 0)
			(type default)
		)
	)
	(wire
		(pts
			(xy 229.362 143.51) (xy 245.11 143.51)
		)
		(stroke
			(width 0)
			(type default)
		)
	)
	(wire
		(pts
			(xy 59.055 175.26) (xy 66.675 175.26)
		)
		(stroke
			(width 0)
			(type default)
		)
	)
	(wire
		(pts
			(xy 111.76 119.38) (xy 109.855 119.38)
		)
		(stroke
			(width 0)
			(type default)
		)
	)
	(wire
		(pts
			(xy 48.387 117.475) (xy 48.387 120.015)
		)
		(stroke
			(width 0)
			(type default)
		)
	)
	(wire
		(pts
			(xy 156.21 231.14) (xy 156.21 232.41)
		)
		(stroke
			(width 0)
			(type default)
		)
	)
	(wire
		(pts
			(xy 101.6 46.99) (xy 101.6 49.53)
		)
		(stroke
			(width 0)
			(type default)
		)
	)
	(wire
		(pts
			(xy 39.497 139.065) (xy 51.308 139.065)
		)
		(stroke
			(width 0)
			(type default)
		)
	)
	(wire
		(pts
			(xy 70.485 62.23) (xy 81.915 62.23)
		)
		(stroke
			(width 0)
			(type default)
		)
	)
	(wire
		(pts
			(xy 63.627 117.475) (xy 63.627 120.015)
		)
		(stroke
			(width 0)
			(type default)
		)
	)
	(wire
		(pts
			(xy 264.16 200.66) (xy 264.16 201.93)
		)
		(stroke
			(width 0)
			(type default)
		)
	)
	(wire
		(pts
			(xy 67.31 64.77) (xy 68.58 64.77)
		)
		(stroke
			(width 0)
			(type default)
		)
	)
	(bus
		(pts
			(xy 329.565 107.315) (xy 329.565 109.855)
		)
		(stroke
			(width 0)
			(type default)
		)
	)
	(wire
		(pts
			(xy 262.89 104.775) (xy 281.94 104.775)
		)
		(stroke
			(width 0)
			(type default)
		)
	)
	(wire
		(pts
			(xy 83.82 80.01) (xy 67.31 80.01)
		)
		(stroke
			(width 0)
			(type default)
		)
	)
	(wire
		(pts
			(xy 133.985 228.6) (xy 141.605 228.6)
		)
		(stroke
			(width 0)
			(type default)
		)
	)
	(wire
		(pts
			(xy 58.547 139.065) (xy 66.802 139.065)
		)
		(stroke
			(width 0)
			(type default)
		)
	)
	(bus
		(pts
			(xy 329.565 170.18) (xy 329.565 171.45)
		)
		(stroke
			(width 0)
			(type default)
		)
	)
	(wire
		(pts
			(xy 295.91 144.78) (xy 310.515 144.78)
		)
		(stroke
			(width 0)
			(type default)
		)
	)
	(wire
		(pts
			(xy 307.34 130.175) (xy 307.34 129.54)
		)
		(stroke
			(width 0)
			(type default)
		)
	)
	(wire
		(pts
			(xy 243.84 140.97) (xy 243.84 148.59)
		)
		(stroke
			(width 0)
			(type default)
		)
	)
	(wire
		(pts
			(xy 281.94 102.235) (xy 285.115 102.235)
		)
		(stroke
			(width 0)
			(type default)
		)
	)
	(wire
		(pts
			(xy 372.11 188.595) (xy 372.11 186.055)
		)
		(stroke
			(width 0)
			(type default)
		)
	)
	(wire
		(pts
			(xy 83.82 238.76) (xy 90.17 238.76)
		)
		(stroke
			(width 0)
			(type default)
		)
	)
	(wire
		(pts
			(xy 109.855 119.38) (xy 109.855 116.84)
		)
		(stroke
			(width 0)
			(type default)
		)
	)
	(wire
		(pts
			(xy 93.345 185.42) (xy 93.345 186.69)
		)
		(stroke
			(width 0)
			(type default)
		)
	)
	(wire
		(pts
			(xy 281.305 135.89) (xy 298.45 135.89)
		)
		(stroke
			(width 0)
			(type default)
		)
	)
	(wire
		(pts
			(xy 83.82 246.38) (xy 83.82 252.095)
		)
		(stroke
			(width 0)
			(type default)
		)
	)
	(wire
		(pts
			(xy 152.4 146.05) (xy 179.705 146.05)
		)
		(stroke
			(width 0)
			(type default)
		)
	)
	(wire
		(pts
			(xy 96.52 166.37) (xy 111.76 166.37)
		)
		(stroke
			(width 0)
			(type default)
		)
	)
	(wire
		(pts
			(xy 83.82 246.38) (xy 90.17 246.38)
		)
		(stroke
			(width 0)
			(type default)
		)
	)
	(wire
		(pts
			(xy 307.34 135.255) (xy 307.34 138.43)
		)
		(stroke
			(width 0)
			(type default)
		)
	)
	(wire
		(pts
			(xy 310.515 129.54) (xy 310.515 130.175)
		)
		(stroke
			(width 0)
			(type default)
		)
	)
	(wire
		(pts
			(xy 268.605 135.89) (xy 268.605 133.35)
		)
		(stroke
			(width 0)
			(type default)
		)
	)
	(wire
		(pts
			(xy 83.185 241.3) (xy 83.185 239.395)
		)
		(stroke
			(width 0)
			(type default)
		)
	)
	(wire
		(pts
			(xy 371.602 129.54) (xy 371.602 127)
		)
		(stroke
			(width 0)
			(type default)
		)
	)
	(bus
		(pts
			(xy 205.105 133.985) (xy 203.2 133.985)
		)
		(stroke
			(width 0)
			(type default)
		)
	)
	(wire
		(pts
			(xy 184.785 138.43) (xy 200.025 138.43)
		)
		(stroke
			(width 0)
			(type default)
		)
	)
	(wire
		(pts
			(xy 262.89 135.89) (xy 268.605 135.89)
		)
		(stroke
			(width 0)
			(type default)
		)
	)
	(wire
		(pts
			(xy 83.185 243.84) (xy 90.17 243.84)
		)
		(stroke
			(width 0)
			(type default)
		)
	)
	(wire
		(pts
			(xy 109.22 208.28) (xy 109.22 210.185)
		)
		(stroke
			(width 0)
			(type default)
		)
	)
	(wire
		(pts
			(xy 287.02 146.05) (xy 287.02 144.78)
		)
		(stroke
			(width 0)
			(type default)
		)
	)
	(wire
		(pts
			(xy 359.41 127) (xy 350.52 127)
		)
		(stroke
			(width 0)
			(type default)
		)
	)
	(wire
		(pts
			(xy 184.785 146.05) (xy 200.025 146.05)
		)
		(stroke
			(width 0)
			(type default)
		)
	)
	(wire
		(pts
			(xy 67.31 62.23) (xy 70.485 62.23)
		)
		(stroke
			(width 0)
			(type default)
		)
	)
	(bus
		(pts
			(xy 329.565 103.505) (xy 329.565 104.775)
		)
		(stroke
			(width 0)
			(type default)
		)
	)
	(wire
		(pts
			(xy 262.89 179.07) (xy 264.16 179.07)
		)
		(stroke
			(width 0)
			(type default)
		)
	)
	(wire
		(pts
			(xy 68.58 252.095) (xy 73.025 252.095)
		)
		(stroke
			(width 0)
			(type default)
		)
	)
	(wire
		(pts
			(xy 136.525 46.99) (xy 136.525 49.53)
		)
		(stroke
			(width 0)
			(type default)
		)
	)
	(wire
		(pts
			(xy 277.495 107.315) (xy 327.025 107.315)
		)
		(stroke
			(width 0)
			(type default)
		)
	)
	(wire
		(pts
			(xy 68.58 245.745) (xy 73.025 245.745)
		)
		(stroke
			(width 0)
			(type default)
		)
	)
	(wire
		(pts
			(xy 245.11 148.59) (xy 243.84 148.59)
		)
		(stroke
			(width 0)
			(type default)
		)
	)
	(wire
		(pts
			(xy 68.58 245.745) (xy 68.58 252.095)
		)
		(stroke
			(width 0)
			(type default)
		)
	)
	(wire
		(pts
			(xy 310.515 135.255) (xy 310.515 144.78)
		)
		(stroke
			(width 0)
			(type default)
		)
	)
	(bus
		(pts
			(xy 332.105 102.87) (xy 330.2 102.87)
		)
		(stroke
			(width 0)
			(type default)
		)
	)
	(wire
		(pts
			(xy 111.76 208.28) (xy 109.22 208.28)
		)
		(stroke
			(width 0)
			(type default)
		)
	)
	(bus
		(pts
			(xy 330.2 133.985) (xy 329.565 134.62)
		)
		(stroke
			(width 0)
			(type default)
		)
	)
	(wire
		(pts
			(xy 360.045 188.595) (xy 360.045 186.055)
		)
		(stroke
			(width 0)
			(type default)
		)
	)
	(wire
		(pts
			(xy 223.52 198.12) (xy 245.11 198.12)
		)
		(stroke
			(width 0)
			(type default)
		)
	)
	(wire
		(pts
			(xy 262.89 143.51) (xy 279.4 143.51)
		)
		(stroke
			(width 0)
			(type default)
		)
	)
	(wire
		(pts
			(xy 59.055 175.26) (xy 59.055 177.8)
		)
		(stroke
			(width 0)
			(type default)
		)
	)
	(wire
		(pts
			(xy 132.08 236.22) (xy 133.985 236.22)
		)
		(stroke
			(width 0)
			(type default)
		)
	)
	(wire
		(pts
			(xy 133.35 248.92) (xy 133.35 250.19)
		)
		(stroke
			(width 0)
			(type default)
		)
	)
	(wire
		(pts
			(xy 152.4 162.56) (xy 175.26 162.56)
		)
		(stroke
			(width 0)
			(type default)
		)
	)
	(wire
		(pts
			(xy 83.82 87.63) (xy 80.645 87.63)
		)
		(stroke
			(width 0)
			(type default)
		)
	)
	(wire
		(pts
			(xy 57.658 161.29) (xy 57.658 158.75)
		)
		(stroke
			(width 0)
			(type default)
		)
	)
	(wire
		(pts
			(xy 152.4 181.61) (xy 175.26 181.61)
		)
		(stroke
			(width 0)
			(type default)
		)
	)
	(bus
		(pts
			(xy 330.2 169.545) (xy 329.565 170.18)
		)
		(stroke
			(width 0)
			(type default)
		)
	)
	(wire
		(pts
			(xy 152.4 124.46) (xy 173.355 124.46)
		)
		(stroke
			(width 0)
			(type default)
		)
	)
	(wire
		(pts
			(xy 58.547 139.065) (xy 58.547 140.97)
		)
		(stroke
			(width 0)
			(type default)
		)
	)
	(wire
		(pts
			(xy 122.555 92.075) (xy 122.555 93.345)
		)
		(stroke
			(width 0)
			(type default)
		)
	)
	(bus
		(pts
			(xy 330.2 191.135) (xy 329.565 191.77)
		)
		(stroke
			(width 0)
			(type default)
		)
	)
	(wire
		(pts
			(xy 152.4 151.13) (xy 179.705 151.13)
		)
		(stroke
			(width 0)
			(type default)
		)
	)
	(wire
		(pts
			(xy 264.16 179.07) (xy 264.16 180.34)
		)
		(stroke
			(width 0)
			(type default)
		)
	)
	(label "FTDI.SDA"
		(at 294.64 266.7 270)
		(effects
			(font
				(size 1.27 1.27)
			)
			(justify right bottom)
		)
	)
	(label "AUX.TDO"
		(at 200.025 143.51 180)
		(effects
			(font
				(size 1.27 1.27)
			)
			(justify right bottom)
		)
	)
	(label "FTDI_PWREN"
		(at 146.05 233.68 180)
		(effects
			(font
				(size 1.27 1.27)
			)
			(justify right bottom)
		)
	)
	(label "FTDI_3V3"
		(at 350.52 127 0)
		(effects
			(font
				(size 1.27 1.27)
			)
			(justify left bottom)
		)
	)
	(label "FTDI_SCL"
		(at 264.16 138.43 0)
		(effects
			(font
				(size 1.27 1.27)
			)
			(justify left bottom)
		)
	)
	(label "VBUS"
		(at 101.6 46.99 0)
		(effects
			(font
				(size 1.27 1.27)
			)
			(justify left bottom)
		)
	)
	(label "VBUS"
		(at 68.58 46.99 0)
		(effects
			(font
				(size 1.27 1.27)
			)
			(justify left bottom)
		)
	)
	(label "BDBUS3"
		(at 298.45 133.35 180)
		(effects
			(font
				(size 1.27 1.27)
			)
			(justify right bottom)
		)
	)
	(label "FTDI_EECLK"
		(at 96.52 163.83 0)
		(effects
			(font
				(size 1.27 1.27)
			)
			(justify left bottom)
		)
	)
	(label "FTDI_EEDAT"
		(at 146.05 243.84 180)
		(effects
			(font
				(size 1.27 1.27)
			)
			(justify right bottom)
		)
	)
	(label "BDBUS2"
		(at 229.362 146.05 0)
		(effects
			(font
				(size 1.27 1.27)
			)
			(justify left bottom)
		)
	)
	(label "FTDI.SDA"
		(at 326.39 144.78 180)
		(effects
			(font
				(size 1.27 1.27)
			)
			(justify right bottom)
		)
	)
	(label "JTAG.TMS"
		(at 219.71 266.7 270)
		(effects
			(font
				(size 1.27 1.27)
			)
			(justify right bottom)
		)
	)
	(label "FTDI_3V3"
		(at 352.425 102.235 0)
		(effects
			(font
				(size 1.27 1.27)
			)
			(justify left bottom)
		)
	)
	(label "FTDI_3V3"
		(at 223.52 171.45 0)
		(effects
			(font
				(size 1.27 1.27)
			)
			(justify left bottom)
		)
	)
	(label "JTAG.TCK"
		(at 327.025 109.855 180)
		(effects
			(font
				(size 1.27 1.27)
			)
			(justify right bottom)
		)
	)
	(label "BDBUS0"
		(at 161.29 138.43 180)
		(effects
			(font
				(size 1.27 1.27)
			)
			(justify right bottom)
		)
	)
	(label "AUX.TCK"
		(at 200.025 138.43 180)
		(effects
			(font
				(size 1.27 1.27)
			)
			(justify right bottom)
		)
	)
	(label "FTDI_UART0_TX"
		(at 223.52 176.53 0)
		(effects
			(font
				(size 1.27 1.27)
			)
			(justify left bottom)
		)
	)
	(label "LED_TX0"
		(at 102.87 238.76 0)
		(effects
			(font
				(size 1.27 1.27)
			)
			(justify left bottom)
		)
	)
	(label "FTDI_EECS"
		(at 96.52 161.29 0)
		(effects
			(font
				(size 1.27 1.27)
			)
			(justify left bottom)
		)
	)
	(label "FTDI_VPHY"
		(at 77.597 139.065 180)
		(effects
			(font
				(size 1.27 1.27)
			)
			(justify right bottom)
		)
	)
	(label "BDBUS2"
		(at 161.29 143.51 180)
		(effects
			(font
				(size 1.27 1.27)
			)
			(justify right bottom)
		)
	)
	(label "FTDI_JTAG_TMS"
		(at 173.355 124.46 180)
		(effects
			(font
				(size 1.27 1.27)
			)
			(justify right bottom)
		)
	)
	(label "FTDI_SDA_IN"
		(at 264.16 146.05 0)
		(effects
			(font
				(size 1.27 1.27)
			)
			(justify left bottom)
		)
	)
	(label "FTDI_VCORE"
		(at 96.52 132.08 0)
		(effects
			(font
				(size 1.27 1.27)
			)
			(justify left bottom)
		)
	)
	(label "FTDI.SCL"
		(at 327.025 138.43 180)
		(effects
			(font
				(size 1.27 1.27)
			)
			(justify right bottom)
		)
	)
	(label "FTDI_3V3"
		(at 229.87 102.235 0)
		(effects
			(font
				(size 1.27 1.27)
			)
			(justify left bottom)
		)
	)
	(label "FTDI_JTAG_TMS"
		(at 229.87 107.315 0)
		(effects
			(font
				(size 1.27 1.27)
			)
			(justify left bottom)
		)
	)
	(label "DBG_USB_P"
		(at 81.915 59.69 180)
		(effects
			(font
				(size 1.27 1.27)
			)
			(justify right bottom)
		)
	)
	(label "FTDI_UART0_TX"
		(at 175.26 160.02 180)
		(effects
			(font
				(size 1.27 1.27)
			)
			(justify right bottom)
		)
	)
	(label "UART1.TX"
		(at 322.58 195.58 180)
		(effects
			(font
				(size 1.27 1.27)
			)
			(justify right bottom)
		)
	)
	(label "FTDI_3V3"
		(at 39.497 158.75 0)
		(effects
			(font
				(size 1.27 1.27)
			)
			(justify left bottom)
		)
	)
	(label "FTDI_3V3"
		(at 39.497 117.475 0)
		(effects
			(font
				(size 1.27 1.27)
			)
			(justify left bottom)
		)
	)
	(label "JTAG.TDI"
		(at 232.41 266.7 270)
		(effects
			(font
				(size 1.27 1.27)
			)
			(justify right bottom)
		)
	)
	(label "AUX.TDI"
		(at 200.025 140.97 180)
		(effects
			(font
				(size 1.27 1.27)
			)
			(justify right bottom)
		)
	)
	(label "FTDI_VPHY"
		(at 96.52 127 0)
		(effects
			(font
				(size 1.27 1.27)
			)
			(justify left bottom)
		)
	)
	(label "JTAG.TCK"
		(at 226.06 266.7 270)
		(effects
			(font
				(size 1.27 1.27)
			)
			(justify right bottom)
		)
	)
	(label "FTDI_EECLK"
		(at 146.05 238.76 180)
		(effects
			(font
				(size 1.27 1.27)
			)
			(justify right bottom)
		)
	)
	(label "FTDI_UART0_RX"
		(at 223.52 173.99 0)
		(effects
			(font
				(size 1.27 1.27)
			)
			(justify left bottom)
		)
	)
	(label "FTDI_VPLL"
		(at 76.073 158.75 180)
		(effects
			(font
				(size 1.27 1.27)
			)
			(justify right bottom)
		)
	)
	(label "DBG_USB_N"
		(at 81.915 62.23 180)
		(effects
			(font
				(size 1.27 1.27)
			)
			(justify right bottom)
		)
	)
	(label "FTDI_3V3"
		(at 223.52 193.04 0)
		(effects
			(font
				(size 1.27 1.27)
			)
			(justify left bottom)
		)
	)
	(label "FTDI_3V3"
		(at 146.685 46.99 180)
		(effects
			(font
				(size 1.27 1.27)
			)
			(justify right bottom)
		)
	)
	(label "FTDI_JTAG_TDO"
		(at 229.87 114.935 0)
		(effects
			(font
				(size 1.27 1.27)
			)
			(justify left bottom)
		)
	)
	(label "JTAG.TMS"
		(at 327.025 107.315 180)
		(effects
			(font
				(size 1.27 1.27)
			)
			(justify right bottom)
		)
	)
	(label "JTAG.TDI"
		(at 327.025 112.395 180)
		(effects
			(font
				(size 1.27 1.27)
			)
			(justify right bottom)
		)
	)
	(label "FTDI_JTAG_TCK"
		(at 173.355 116.84 180)
		(effects
			(font
				(size 1.27 1.27)
			)
			(justify right bottom)
		)
	)
	(label "FTDI_JTAG_TDI"
		(at 173.355 119.38 180)
		(effects
			(font
				(size 1.27 1.27)
			)
			(justify right bottom)
		)
	)
	(label "I2C_EN"
		(at 161.29 151.13 180)
		(effects
			(font
				(size 1.27 1.27)
			)
			(justify right bottom)
		)
	)
	(label "FTDI_UART1_RX"
		(at 223.52 195.58 0)
		(effects
			(font
				(size 1.27 1.27)
			)
			(justify left bottom)
		)
	)
	(label "FTDI_XO"
		(at 103.505 176.53 0)
		(effects
			(font
				(size 1.27 1.27)
			)
			(justify left bottom)
		)
	)
	(label "UART1.RX"
		(at 276.86 266.7 270)
		(effects
			(font
				(size 1.27 1.27)
			)
			(justify right bottom)
		)
	)
	(label "FTDI.SCL"
		(at 288.29 266.7 270)
		(effects
			(font
				(size 1.27 1.27)
			)
			(justify right bottom)
		)
	)
	(label "DBG_USB_N"
		(at 96.52 142.24 0)
		(effects
			(font
				(size 1.27 1.27)
			)
			(justify left bottom)
		)
	)
	(label "FTDI_UART1_TX"
		(at 223.52 198.12 0)
		(effects
			(font
				(size 1.27 1.27)
			)
			(justify left bottom)
		)
	)
	(label "FTDI_UART1_TX"
		(at 175.26 181.61 180)
		(effects
			(font
				(size 1.27 1.27)
			)
			(justify right bottom)
		)
	)
	(label "UART0.TX"
		(at 322.58 173.99 180)
		(effects
			(font
				(size 1.27 1.27)
			)
			(justify right bottom)
		)
	)
	(label "FTDI_JTAG_TDO"
		(at 173.355 121.92 180)
		(effects
			(font
				(size 1.27 1.27)
			)
			(justify right bottom)
		)
	)
	(label "UART1.RX"
		(at 322.58 198.12 180)
		(effects
			(font
				(size 1.27 1.27)
			)
			(justify right bottom)
		)
	)
	(label "FTDI_VPLL"
		(at 96.52 129.54 0)
		(effects
			(font
				(size 1.27 1.27)
			)
			(justify left bottom)
		)
	)
	(label "FTDI_JTAG_RST"
		(at 172.72 129.54 180)
		(effects
			(font
				(size 1.27 1.27)
			)
			(justify right bottom)
		)
	)
	(label "I2C_EN"
		(at 298.45 135.89 180)
		(effects
			(font
				(size 1.27 1.27)
			)
			(justify right bottom)
		)
	)
	(label "FTDI_EEDAT"
		(at 96.52 166.37 0)
		(effects
			(font
				(size 1.27 1.27)
			)
			(justify left bottom)
		)
	)
	(label "DBG_USB_N"
		(at 132.715 86.995 180)
		(effects
			(font
				(size 1.27 1.27)
			)
			(justify right bottom)
		)
	)
	(label "FTDI_3V3"
		(at 96.52 116.84 0)
		(effects
			(font
				(size 1.27 1.27)
			)
			(justify left bottom)
		)
	)
	(label "FTDI_UART0_RX"
		(at 175.26 162.56 180)
		(effects
			(font
				(size 1.27 1.27)
			)
			(justify right bottom)
		)
	)
	(label "FTDI_EECS"
		(at 146.05 241.3 180)
		(effects
			(font
				(size 1.27 1.27)
			)
			(justify right bottom)
		)
	)
	(label "JTAG.TDO"
		(at 238.76 266.7 270)
		(effects
			(font
				(size 1.27 1.27)
			)
			(justify right bottom)
		)
	)
	(label "BDBUS3"
		(at 161.29 146.05 180)
		(effects
			(font
				(size 1.27 1.27)
			)
			(justify right bottom)
		)
	)
	(label "DBG_USB_P"
		(at 132.715 84.455 180)
		(effects
			(font
				(size 1.27 1.27)
			)
			(justify right bottom)
		)
	)
	(label "FTDI_3V3"
		(at 165.735 223.52 180)
		(effects
			(font
				(size 1.27 1.27)
			)
			(justify right bottom)
		)
	)
	(label "AUX.RST"
		(at 200.025 151.13 180)
		(effects
			(font
				(size 1.27 1.27)
			)
			(justify right bottom)
		)
	)
	(label "FTDI_JTAG_TCK"
		(at 229.87 109.855 0)
		(effects
			(font
				(size 1.27 1.27)
			)
			(justify left bottom)
		)
	)
	(label "FTDI_3V3"
		(at 351.155 186.055 0)
		(effects
			(font
				(size 1.27 1.27)
			)
			(justify left bottom)
		)
	)
	(label "FTDI_3V3"
		(at 39.497 139.065 0)
		(effects
			(font
				(size 1.27 1.27)
			)
			(justify left bottom)
		)
	)
	(label "UART1.TX"
		(at 270.51 266.7 270)
		(effects
			(font
				(size 1.27 1.27)
			)
			(justify right bottom)
		)
	)
	(label "FTDI_3V3"
		(at 229.362 133.35 0)
		(effects
			(font
				(size 1.27 1.27)
			)
			(justify left bottom)
		)
	)
	(label "BDBUS1"
		(at 229.362 143.51 0)
		(effects
			(font
				(size 1.27 1.27)
			)
			(justify left bottom)
		)
	)
	(label "FTDI_VCORE"
		(at 39.497 175.26 0)
		(effects
			(font
				(size 1.27 1.27)
			)
			(justify left bottom)
		)
	)
	(label "AUX.TMS"
		(at 200.025 146.05 180)
		(effects
			(font
				(size 1.27 1.27)
			)
			(justify right bottom)
		)
	)
	(label "FTDI_UART1_RX"
		(at 175.26 184.15 180)
		(effects
			(font
				(size 1.27 1.27)
			)
			(justify right bottom)
		)
	)
	(label "FTDI_SDA_OUT"
		(at 264.16 143.51 0)
		(effects
			(font
				(size 1.27 1.27)
			)
			(justify left bottom)
		)
	)
	(label "BDBUS1"
		(at 161.29 140.97 180)
		(effects
			(font
				(size 1.27 1.27)
			)
			(justify right bottom)
		)
	)
	(label "FTDI_3V3"
		(at 351.155 166.37 0)
		(effects
			(font
				(size 1.27 1.27)
			)
			(justify left bottom)
		)
	)
	(label "FTDI_XI"
		(at 104.14 171.45 0)
		(effects
			(font
				(size 1.27 1.27)
			)
			(justify left bottom)
		)
	)
	(label "LED_RX1"
		(at 102.87 246.38 0)
		(effects
			(font
				(size 1.27 1.27)
			)
			(justify left bottom)
		)
	)
	(label "UART0.TX"
		(at 257.81 266.7 270)
		(effects
			(font
				(size 1.27 1.27)
			)
			(justify right bottom)
		)
	)
	(label "LED_RX0"
		(at 102.87 241.3 0)
		(effects
			(font
				(size 1.27 1.27)
			)
			(justify left bottom)
		)
	)
	(label "LED_TX1"
		(at 102.87 243.84 0)
		(effects
			(font
				(size 1.27 1.27)
			)
			(justify left bottom)
		)
	)
	(label "DBG_USB_P"
		(at 96.52 139.7 0)
		(effects
			(font
				(size 1.27 1.27)
			)
			(justify left bottom)
		)
	)
	(label "FTDI_JTAG_TDI"
		(at 229.87 112.395 0)
		(effects
			(font
				(size 1.27 1.27)
			)
			(justify left bottom)
		)
	)
	(label "JTAG.TDO"
		(at 327.025 114.935 180)
		(effects
			(font
				(size 1.27 1.27)
			)
			(justify right bottom)
		)
	)
	(label "BDBUS0"
		(at 229.362 138.43 0)
		(effects
			(font
				(size 1.27 1.27)
			)
			(justify left bottom)
		)
	)
	(label "UART0.RX"
		(at 264.16 266.7 270)
		(effects
			(font
				(size 1.27 1.27)
			)
			(justify right bottom)
		)
	)
	(label "FTDI_PWREN"
		(at 164.465 204.47 180)
		(effects
			(font
				(size 1.27 1.27)
			)
			(justify right bottom)
		)
	)
	(label "UART0.RX"
		(at 322.58 176.53 180)
		(effects
			(font
				(size 1.27 1.27)
			)
			(justify right bottom)
		)
	)
	(label "FTDI_3V3"
		(at 96.52 153.67 0)
		(effects
			(font
				(size 1.27 1.27)
			)
			(justify left bottom)
		)
	)
	(global_label "FTDI_DIS"
		(shape input)
		(at 245.11 274.32 90)
		(fields_autoplaced yes)
		(effects
			(font
				(size 1.27 1.27)
			)
			(justify left)
		)
		(property "Intersheetrefs" "${INTERSHEET_REFS}"
			(at 245.11 264.0061 90)
			(effects
				(font
					(size 1.27 1.27)
				)
				(justify left)
			)
		)
	)
	(global_label "FTDI_DIS"
		(shape input)
		(at 285.115 102.235 0)
		(fields_autoplaced yes)
		(effects
			(font
				(size 1.27 1.27)
			)
			(justify left)
		)
		(property "Intersheetrefs" "${INTERSHEET_REFS}"
			(at 295.511 102.3144 0)
			(effects
				(font
					(size 1.27 1.27)
				)
				(justify left)
			)
		)
	)
	(hierarchical_label "FTDI{I^{2}C}"
		(shape bidirectional)
		(at 332.105 133.985 0)
		(effects
			(font
				(size 1.27 1.27)
			)
			(justify left)
		)
	)
	(hierarchical_label "UART1{UART}"
		(shape bidirectional)
		(at 332.105 191.135 0)
		(effects
			(font
				(size 1.27 1.27)
			)
			(justify left)
		)
	)
	(hierarchical_label "JTAG{JTAG}"
		(shape bidirectional)
		(at 332.105 102.87 0)
		(effects
			(font
				(size 1.27 1.27)
			)
			(justify left)
		)
	)
	(hierarchical_label "UART0{UART}"
		(shape bidirectional)
		(at 332.105 169.545 0)
		(effects
			(font
				(size 1.27 1.27)
			)
			(justify left)
		)
	)
	(hierarchical_label "AUX{JTAG}"
		(shape bidirectional)
		(at 205.105 133.985 0)
		(effects
			(font
				(size 1.27 1.27)
			)
			(justify left)
		)
	)
	(symbol
		(lib_id "antmicroResistors0402:R_22R_0402")
		(at 272.415 173.99 0)
		(unit 1)
		(exclude_from_sim no)
		(in_bom yes)
		(on_board yes)
		(dnp no)
		(property "Reference" "R52"
			(at 280.035 172.72 0)
			(effects
				(font
					(size 1.27 1.27)
				)
			)
		)
		(property "Value" "R_22R_0402"
			(at 292.735 186.69 0)
			(effects
				(font
					(size 1.27 1.27)
					(thickness 0.15)
				)
				(justify left bottom)
				(hide yes)
			)
		)
		(property "Footprint" "antmicro-footprints:R_0402_1005Metric"
			(at 292.735 189.23 0)
			(effects
				(font
					(size 1.27 1.27)
					(thickness 0.15)
				)
				(justify left bottom)
				(hide yes)
			)
		)
		(property "Datasheet" "https://www.bourns.com/docs/product-datasheets/cr.pdf"
			(at 292.735 191.77 0)
			(effects
				(font
					(size 1.27 1.27)
					(thickness 0.15)
				)
				(justify left bottom)
				(hide yes)
			)
		)
		(property "Description" ""
			(at 272.415 173.99 0)
			(effects
				(font
					(size 1.27 1.27)
				)
			)
		)
		(property "Manufacturer" "Bourns"
			(at 292.735 196.85 0)
			(effects
				(font
					(size 1.27 1.27)
					(thickness 0.15)
				)
				(justify left bottom)
				(hide yes)
			)
		)
		(property "MPN" "CR0402-FX-22R0GLF"
			(at 292.735 194.31 0)
			(effects
				(font
					(size 1.27 1.27)
					(thickness 0.15)
				)
				(justify left bottom)
				(hide yes)
			)
		)
		(property "Val" "22R"
			(at 270.51 172.72 0)
			(effects
				(font
					(size 1.27 1.27)
					(thickness 0.15)
				)
			)
		)
		(property "License" "Apache-2.0"
			(at 292.735 199.39 0)
			(effects
				(font
					(size 1.27 1.27)
					(thickness 0.15)
				)
				(justify left bottom)
				(hide yes)
			)
		)
		(property "Author" "Antmicro"
			(at 292.735 201.93 0)
			(effects
				(font
					(size 1.27 1.27)
					(thickness 0.15)
				)
				(justify left bottom)
				(hide yes)
			)
		)
		(property "Tolerance" "1%"
			(at 292.735 184.15 0)
			(effects
				(font
					(size 1.27 1.27)
				)
				(justify left bottom)
				(hide yes)
			)
		)
		(pin "1"
		)
		(pin "2"
		)
		(instances
			(project "sodimm-ddr5-tester"
				(path ""
					(reference "R52")
					(unit 1)
				)
			)
		)
	)
	(symbol
		(lib_id "antmicroResistors0402:R_22R_0402")
		(at 272.415 198.12 0)
		(unit 1)
		(exclude_from_sim no)
		(in_bom yes)
		(on_board yes)
		(dnp no)
		(property "Reference" "R55"
			(at 279.4 196.85 0)
			(effects
				(font
					(size 1.27 1.27)
				)
			)
		)
		(property "Value" "R_22R_0402"
			(at 292.735 210.82 0)
			(effects
				(font
					(size 1.27 1.27)
					(thickness 0.15)
				)
				(justify left bottom)
				(hide yes)
			)
		)
		(property "Footprint" "antmicro-footprints:R_0402_1005Metric"
			(at 292.735 213.36 0)
			(effects
				(font
					(size 1.27 1.27)
					(thickness 0.15)
				)
				(justify left bottom)
				(hide yes)
			)
		)
		(property "Datasheet" "https://www.bourns.com/docs/product-datasheets/cr.pdf"
			(at 292.735 215.9 0)
			(effects
				(font
					(size 1.27 1.27)
					(thickness 0.15)
				)
				(justify left bottom)
				(hide yes)
			)
		)
		(property "Description" ""
			(at 272.415 198.12 0)
			(effects
				(font
					(size 1.27 1.27)
				)
			)
		)
		(property "Manufacturer" "Bourns"
			(at 292.735 220.98 0)
			(effects
				(font
					(size 1.27 1.27)
					(thickness 0.15)
				)
				(justify left bottom)
				(hide yes)
			)
		)
		(property "MPN" "CR0402-FX-22R0GLF"
			(at 292.735 218.44 0)
			(effects
				(font
					(size 1.27 1.27)
					(thickness 0.15)
				)
				(justify left bottom)
				(hide yes)
			)
		)
		(property "Val" "22R"
			(at 270.51 196.85 0)
			(effects
				(font
					(size 1.27 1.27)
					(thickness 0.15)
				)
			)
		)
		(property "License" "Apache-2.0"
			(at 292.735 223.52 0)
			(effects
				(font
					(size 1.27 1.27)
					(thickness 0.15)
				)
				(justify left bottom)
				(hide yes)
			)
		)
		(property "Author" "Antmicro"
			(at 292.735 226.06 0)
			(effects
				(font
					(size 1.27 1.27)
					(thickness 0.15)
				)
				(justify left bottom)
				(hide yes)
			)
		)
		(property "Tolerance" "1%"
			(at 292.735 208.28 0)
			(effects
				(font
					(size 1.27 1.27)
				)
				(justify left bottom)
				(hide yes)
			)
		)
		(pin "1"
		)
		(pin "2"
		)
		(instances
			(project "sodimm-ddr5-tester"
				(path ""
					(reference "R55")
					(unit 1)
				)
			)
		)
	)
	(symbol
		(lib_id "antmicroResistors0402:R_22R_0402")
		(at 272.415 176.53 0)
		(unit 1)
		(exclude_from_sim no)
		(in_bom yes)
		(on_board yes)
		(dnp no)
		(property "Reference" "R53"
			(at 280.035 175.26 0)
			(effects
				(font
					(size 1.27 1.27)
				)
			)
		)
		(property "Value" "R_22R_0402"
			(at 292.735 189.23 0)
			(effects
				(font
					(size 1.27 1.27)
					(thickness 0.15)
				)
				(justify left bottom)
				(hide yes)
			)
		)
		(property "Footprint" "antmicro-footprints:R_0402_1005Metric"
			(at 292.735 191.77 0)
			(effects
				(font
					(size 1.27 1.27)
					(thickness 0.15)
				)
				(justify left bottom)
				(hide yes)
			)
		)
		(property "Datasheet" "https://www.bourns.com/docs/product-datasheets/cr.pdf"
			(at 292.735 194.31 0)
			(effects
				(font
					(size 1.27 1.27)
					(thickness 0.15)
				)
				(justify left bottom)
				(hide yes)
			)
		)
		(property "Description" ""
			(at 272.415 176.53 0)
			(effects
				(font
					(size 1.27 1.27)
				)
			)
		)
		(property "Manufacturer" "Bourns"
			(at 292.735 199.39 0)
			(effects
				(font
					(size 1.27 1.27)
					(thickness 0.15)
				)
				(justify left bottom)
				(hide yes)
			)
		)
		(property "MPN" "CR0402-FX-22R0GLF"
			(at 292.735 196.85 0)
			(effects
				(font
					(size 1.27 1.27)
					(thickness 0.15)
				)
				(justify left bottom)
				(hide yes)
			)
		)
		(property "Val" "22R"
			(at 270.51 175.26 0)
			(effects
				(font
					(size 1.27 1.27)
					(thickness 0.15)
				)
			)
		)
		(property "License" "Apache-2.0"
			(at 292.735 201.93 0)
			(effects
				(font
					(size 1.27 1.27)
					(thickness 0.15)
				)
				(justify left bottom)
				(hide yes)
			)
		)
		(property "Author" "Antmicro"
			(at 292.735 204.47 0)
			(effects
				(font
					(size 1.27 1.27)
					(thickness 0.15)
				)
				(justify left bottom)
				(hide yes)
			)
		)
		(property "Tolerance" "1%"
			(at 292.735 186.69 0)
			(effects
				(font
					(size 1.27 1.27)
				)
				(justify left bottom)
				(hide yes)
			)
		)
		(pin "1"
		)
		(pin "2"
		)
		(instances
			(project "sodimm-ddr5-tester"
				(path ""
					(reference "R53")
					(unit 1)
				)
			)
		)
	)
	(symbol
		(lib_id "antmicroResistors0402:R_22R_0402")
		(at 272.415 195.58 0)
		(unit 1)
		(exclude_from_sim no)
		(in_bom yes)
		(on_board yes)
		(dnp no)
		(property "Reference" "R54"
			(at 279.4 194.31 0)
			(effects
				(font
					(size 1.27 1.27)
				)
			)
		)
		(property "Value" "R_22R_0402"
			(at 292.735 208.28 0)
			(effects
				(font
					(size 1.27 1.27)
					(thickness 0.15)
				)
				(justify left bottom)
				(hide yes)
			)
		)
		(property "Footprint" "antmicro-footprints:R_0402_1005Metric"
			(at 292.735 210.82 0)
			(effects
				(font
					(size 1.27 1.27)
					(thickness 0.15)
				)
				(justify left bottom)
				(hide yes)
			)
		)
		(property "Datasheet" "https://www.bourns.com/docs/product-datasheets/cr.pdf"
			(at 292.735 213.36 0)
			(effects
				(font
					(size 1.27 1.27)
					(thickness 0.15)
				)
				(justify left bottom)
				(hide yes)
			)
		)
		(property "Description" ""
			(at 272.415 195.58 0)
			(effects
				(font
					(size 1.27 1.27)
				)
			)
		)
		(property "Manufacturer" "Bourns"
			(at 292.735 218.44 0)
			(effects
				(font
					(size 1.27 1.27)
					(thickness 0.15)
				)
				(justify left bottom)
				(hide yes)
			)
		)
		(property "MPN" "CR0402-FX-22R0GLF"
			(at 292.735 215.9 0)
			(effects
				(font
					(size 1.27 1.27)
					(thickness 0.15)
				)
				(justify left bottom)
				(hide yes)
			)
		)
		(property "Val" "22R"
			(at 270.51 194.31 0)
			(effects
				(font
					(size 1.27 1.27)
					(thickness 0.15)
				)
			)
		)
		(property "License" "Apache-2.0"
			(at 292.735 220.98 0)
			(effects
				(font
					(size 1.27 1.27)
					(thickness 0.15)
				)
				(justify left bottom)
				(hide yes)
			)
		)
		(property "Author" "Antmicro"
			(at 292.735 223.52 0)
			(effects
				(font
					(size 1.27 1.27)
					(thickness 0.15)
				)
				(justify left bottom)
				(hide yes)
			)
		)
		(property "Tolerance" "1%"
			(at 292.735 205.74 0)
			(effects
				(font
					(size 1.27 1.27)
				)
				(justify left bottom)
				(hide yes)
			)
		)
		(pin "1"
		)
		(pin "2"
		)
		(instances
			(project "sodimm-ddr5-tester"
				(path ""
					(reference "R54")
					(unit 1)
				)
			)
		)
	)
	(symbol
		(lib_id "antmicroCapacitors0402:C_100n_0402")
		(at 66.802 140.97 270)
		(unit 1)
		(exclude_from_sim no)
		(in_bom yes)
		(on_board yes)
		(dnp no)
		(property "Reference" "C112"
			(at 67.437 141.605 90)
			(effects
				(font
					(size 1.27 1.27)
				)
				(justify left)
			)
		)
		(property "Value" "C_100n_0402"
			(at 56.642 161.29 0)
			(effects
				(font
					(size 1.27 1.27)
					(thickness 0.15)
				)
				(justify left bottom)
				(hide yes)
			)
		)
		(property "Footprint" "antmicro-footprints:C_0402_1005Metric"
			(at 54.102 161.29 0)
			(effects
				(font
					(size 1.27 1.27)
					(thickness 0.15)
				)
				(justify left bottom)
				(hide yes)
			)
		)
		(property "Datasheet" "https://www.murata.com/products/productdetail?partno=GRM155R61H104KE14%23"
			(at 51.562 161.29 0)
			(effects
				(font
					(size 1.27 1.27)
					(thickness 0.15)
				)
				(justify left bottom)
				(hide yes)
			)
		)
		(property "Description" ""
			(at 66.802 140.97 0)
			(effects
				(font
					(size 1.27 1.27)
				)
			)
		)
		(property "Manufacturer" "Murata"
			(at 46.482 161.29 0)
			(effects
				(font
					(size 1.27 1.27)
					(thickness 0.15)
				)
				(justify left bottom)
				(hide yes)
			)
		)
		(property "MPN" "GRM155R61H104KE14D"
			(at 49.022 161.29 0)
			(effects
				(font
					(size 1.27 1.27)
					(thickness 0.15)
				)
				(justify left bottom)
				(hide yes)
			)
		)
		(property "Val" "100n"
			(at 67.437 145.415 90)
			(effects
				(font
					(size 1.27 1.27)
					(thickness 0.15)
				)
				(justify left)
			)
		)
		(property "License" "Apache-2.0"
			(at 43.942 161.29 0)
			(effects
				(font
					(size 1.27 1.27)
					(thickness 0.15)
				)
				(justify left bottom)
				(hide yes)
			)
		)
		(property "Author" "Antmicro"
			(at 41.402 161.29 0)
			(effects
				(font
					(size 1.27 1.27)
					(thickness 0.15)
				)
				(justify left bottom)
				(hide yes)
			)
		)
		(property "Voltage" "50V"
			(at 38.862 161.29 0)
			(effects
				(font
					(size 1.27 1.27)
				)
				(justify left bottom)
				(hide yes)
			)
		)
		(property "Dielectric" "X5R"
			(at 36.322 161.29 0)
			(effects
				(font
					(size 1.27 1.27)
				)
				(justify left bottom)
				(hide yes)
			)
		)
		(pin "1"
		)
		(pin "2"
		)
		(instances
			(project "sodimm-ddr5-tester"
				(path ""
					(reference "C112")
					(unit 1)
				)
			)
		)
	)
	(symbol
		(lib_id "antmicroCapacitors0402:C_4u7_0402")
		(at 58.547 140.97 270)
		(unit 1)
		(exclude_from_sim no)
		(in_bom yes)
		(on_board yes)
		(dnp no)
		(property "Reference" "C116"
			(at 64.262 141.605 90)
			(effects
				(font
					(size 1.27 1.27)
				)
				(justify right)
			)
		)
		(property "Value" "C_4u7_0402"
			(at 48.387 161.29 0)
			(effects
				(font
					(size 1.27 1.27)
					(thickness 0.15)
				)
				(justify left bottom)
				(hide yes)
			)
		)
		(property "Footprint" "antmicro-footprints:C_0402_1005Metric"
			(at 45.847 161.29 0)
			(effects
				(font
					(size 1.27 1.27)
					(thickness 0.15)
				)
				(justify left bottom)
				(hide yes)
			)
		)
		(property "Datasheet" "https://www.murata.com/products/productdetail?partno=GRM155R61A475MEAA%23"
			(at 43.307 161.29 0)
			(effects
				(font
					(size 1.27 1.27)
					(thickness 0.15)
				)
				(justify left bottom)
				(hide yes)
			)
		)
		(property "Description" ""
			(at 58.547 140.97 0)
			(effects
				(font
					(size 1.27 1.27)
				)
			)
		)
		(property "Manufacturer" "Murata"
			(at 38.227 161.29 0)
			(effects
				(font
					(size 1.27 1.27)
					(thickness 0.15)
				)
				(justify left bottom)
				(hide yes)
			)
		)
		(property "MPN" "GRM155R61A475MEAAD"
			(at 40.767 161.29 0)
			(effects
				(font
					(size 1.27 1.27)
					(thickness 0.15)
				)
				(justify left bottom)
				(hide yes)
			)
		)
		(property "Val" "4u7"
			(at 62.992 145.415 90)
			(effects
				(font
					(size 1.27 1.27)
					(thickness 0.15)
				)
				(justify right)
			)
		)
		(property "License" "Apache-2.0"
			(at 35.687 161.29 0)
			(effects
				(font
					(size 1.27 1.27)
					(thickness 0.15)
				)
				(justify left bottom)
				(hide yes)
			)
		)
		(property "Author" "Antmicro"
			(at 33.147 161.29 0)
			(effects
				(font
					(size 1.27 1.27)
					(thickness 0.15)
				)
				(justify left bottom)
				(hide yes)
			)
		)
		(property "Voltage" ""
			(at 30.607 161.29 0)
			(effects
				(font
					(size 1.27 1.27)
				)
				(justify left bottom)
				(hide yes)
			)
		)
		(property "Dielectric" ""
			(at 28.067 161.29 0)
			(effects
				(font
					(size 1.27 1.27)
				)
				(justify left bottom)
				(hide yes)
			)
		)
		(pin "1"
		)
		(pin "2"
		)
		(instances
			(project "sodimm-ddr5-tester"
				(path ""
					(reference "C116")
					(unit 1)
				)
			)
		)
	)
	(symbol
		(lib_id "antmicroCapacitors0402:C_100n_0402")
		(at 65.532 161.29 270)
		(unit 1)
		(exclude_from_sim no)
		(in_bom yes)
		(on_board yes)
		(dnp no)
		(property "Reference" "C110"
			(at 66.167 161.925 90)
			(effects
				(font
					(size 1.27 1.27)
				)
				(justify left)
			)
		)
		(property "Value" "C_100n_0402"
			(at 55.372 181.61 0)
			(effects
				(font
					(size 1.27 1.27)
					(thickness 0.15)
				)
				(justify left bottom)
				(hide yes)
			)
		)
		(property "Footprint" "antmicro-footprints:C_0402_1005Metric"
			(at 52.832 181.61 0)
			(effects
				(font
					(size 1.27 1.27)
					(thickness 0.15)
				)
				(justify left bottom)
				(hide yes)
			)
		)
		(property "Datasheet" "https://www.murata.com/products/productdetail?partno=GRM155R61H104KE14%23"
			(at 50.292 181.61 0)
			(effects
				(font
					(size 1.27 1.27)
					(thickness 0.15)
				)
				(justify left bottom)
				(hide yes)
			)
		)
		(property "Description" ""
			(at 65.532 161.29 0)
			(effects
				(font
					(size 1.27 1.27)
				)
			)
		)
		(property "Manufacturer" "Murata"
			(at 45.212 181.61 0)
			(effects
				(font
					(size 1.27 1.27)
					(thickness 0.15)
				)
				(justify left bottom)
				(hide yes)
			)
		)
		(property "MPN" "GRM155R61H104KE14D"
			(at 47.752 181.61 0)
			(effects
				(font
					(size 1.27 1.27)
					(thickness 0.15)
				)
				(justify left bottom)
				(hide yes)
			)
		)
		(property "Val" "100n"
			(at 66.167 165.735 90)
			(effects
				(font
					(size 1.27 1.27)
					(thickness 0.15)
				)
				(justify left)
			)
		)
		(property "License" "Apache-2.0"
			(at 42.672 181.61 0)
			(effects
				(font
					(size 1.27 1.27)
					(thickness 0.15)
				)
				(justify left bottom)
				(hide yes)
			)
		)
		(property "Author" "Antmicro"
			(at 40.132 181.61 0)
			(effects
				(font
					(size 1.27 1.27)
					(thickness 0.15)
				)
				(justify left bottom)
				(hide yes)
			)
		)
		(property "Voltage" "50V"
			(at 37.592 181.61 0)
			(effects
				(font
					(size 1.27 1.27)
				)
				(justify left bottom)
				(hide yes)
			)
		)
		(property "Dielectric" "X5R"
			(at 35.052 181.61 0)
			(effects
				(font
					(size 1.27 1.27)
				)
				(justify left bottom)
				(hide yes)
			)
		)
		(pin "1"
		)
		(pin "2"
		)
		(instances
			(project "sodimm-ddr5-tester"
				(path ""
					(reference "C110")
					(unit 1)
				)
			)
		)
	)
	(symbol
		(lib_id "antmicroCapacitors0402:C_4u7_0402")
		(at 57.658 161.29 270)
		(unit 1)
		(exclude_from_sim no)
		(in_bom yes)
		(on_board yes)
		(dnp no)
		(property "Reference" "C114"
			(at 58.293 161.925 90)
			(effects
				(font
					(size 1.27 1.27)
				)
				(justify left)
			)
		)
		(property "Value" "C_4u7_0402"
			(at 47.498 181.61 0)
			(effects
				(font
					(size 1.27 1.27)
					(thickness 0.15)
				)
				(justify left bottom)
				(hide yes)
			)
		)
		(property "Footprint" "antmicro-footprints:C_0402_1005Metric"
			(at 44.958 181.61 0)
			(effects
				(font
					(size 1.27 1.27)
					(thickness 0.15)
				)
				(justify left bottom)
				(hide yes)
			)
		)
		(property "Datasheet" "https://www.murata.com/products/productdetail?partno=GRM155R61A475MEAA%23"
			(at 42.418 181.61 0)
			(effects
				(font
					(size 1.27 1.27)
					(thickness 0.15)
				)
				(justify left bottom)
				(hide yes)
			)
		)
		(property "Description" ""
			(at 57.658 161.29 0)
			(effects
				(font
					(size 1.27 1.27)
				)
			)
		)
		(property "Manufacturer" "Murata"
			(at 37.338 181.61 0)
			(effects
				(font
					(size 1.27 1.27)
					(thickness 0.15)
				)
				(justify left bottom)
				(hide yes)
			)
		)
		(property "MPN" "GRM155R61A475MEAAD"
			(at 39.878 181.61 0)
			(effects
				(font
					(size 1.27 1.27)
					(thickness 0.15)
				)
				(justify left bottom)
				(hide yes)
			)
		)
		(property "Val" "4u7"
			(at 58.293 165.735 90)
			(effects
				(font
					(size 1.27 1.27)
					(thickness 0.15)
				)
				(justify left)
			)
		)
		(property "License" "Apache-2.0"
			(at 34.798 181.61 0)
			(effects
				(font
					(size 1.27 1.27)
					(thickness 0.15)
				)
				(justify left bottom)
				(hide yes)
			)
		)
		(property "Author" "Antmicro"
			(at 32.258 181.61 0)
			(effects
				(font
					(size 1.27 1.27)
					(thickness 0.15)
				)
				(justify left bottom)
				(hide yes)
			)
		)
		(property "Voltage" ""
			(at 29.718 181.61 0)
			(effects
				(font
					(size 1.27 1.27)
				)
				(justify left bottom)
				(hide yes)
			)
		)
		(property "Dielectric" ""
			(at 27.178 181.61 0)
			(effects
				(font
					(size 1.27 1.27)
				)
				(justify left bottom)
				(hide yes)
			)
		)
		(pin "1"
		)
		(pin "2"
		)
		(instances
			(project "sodimm-ddr5-tester"
				(path ""
					(reference "C114")
					(unit 1)
				)
			)
		)
	)
	(symbol
		(lib_id "antmicroResistors0402:R_12k_0402")
		(at 109.22 202.565 90)
		(unit 1)
		(exclude_from_sim no)
		(in_bom yes)
		(on_board yes)
		(dnp no)
		(fields_autoplaced yes)
		(property "Reference" "R44"
			(at 107.315 198.755 90)
			(effects
				(font
					(size 1.27 1.27)
				)
				(justify left)
			)
		)
		(property "Value" "R_12k_0402"
			(at 121.92 182.245 0)
			(effects
				(font
					(size 1.27 1.27)
					(thickness 0.15)
				)
				(justify left bottom)
				(hide yes)
			)
		)
		(property "Footprint" "antmicro-footprints:R_0402_1005Metric"
			(at 124.46 182.245 0)
			(effects
				(font
					(size 1.27 1.27)
					(thickness 0.15)
				)
				(justify left bottom)
				(hide yes)
			)
		)
		(property "Datasheet" "https://www.bourns.com/docs/product-datasheets/cr.pdf"
			(at 127 182.245 0)
			(effects
				(font
					(size 1.27 1.27)
					(thickness 0.15)
				)
				(justify left bottom)
				(hide yes)
			)
		)
		(property "Description" ""
			(at 109.22 202.565 0)
			(effects
				(font
					(size 1.27 1.27)
				)
			)
		)
		(property "Manufacturer" "Bourns"
			(at 132.08 182.245 0)
			(effects
				(font
					(size 1.27 1.27)
					(thickness 0.15)
				)
				(justify left bottom)
				(hide yes)
			)
		)
		(property "MPN" "CR0402-FX-1202GLF"
			(at 129.54 182.245 0)
			(effects
				(font
					(size 1.27 1.27)
					(thickness 0.15)
				)
				(justify left bottom)
				(hide yes)
			)
		)
		(property "Val" "12k"
			(at 107.315 201.9299 90)
			(effects
				(font
					(size 1.27 1.27)
					(thickness 0.15)
				)
				(justify left)
			)
		)
		(property "License" "Apache-2.0"
			(at 134.62 182.245 0)
			(effects
				(font
					(size 1.27 1.27)
					(thickness 0.15)
				)
				(justify left bottom)
				(hide yes)
			)
		)
		(property "Author" "Antmicro"
			(at 137.16 182.245 0)
			(effects
				(font
					(size 1.27 1.27)
					(thickness 0.15)
				)
				(justify left bottom)
				(hide yes)
			)
		)
		(property "Tolerance" "1%"
			(at 119.38 182.245 0)
			(effects
				(font
					(size 1.27 1.27)
				)
				(justify left bottom)
				(hide yes)
			)
		)
		(pin "1"
		)
		(pin "2"
		)
		(instances
			(project "sodimm-ddr5-tester"
				(path ""
					(reference "R44")
					(unit 1)
				)
			)
		)
	)
	(symbol
		(lib_id "antmicroResistors0402:R_10k_0402")
		(at 105.41 153.67 0)
		(unit 1)
		(exclude_from_sim no)
		(in_bom yes)
		(on_board yes)
		(dnp no)
		(property "Reference" "R43"
			(at 107.95 148.59 0)
			(effects
				(font
					(size 1.27 1.27)
				)
			)
		)
		(property "Value" "R_10k_0402"
			(at 125.73 166.37 0)
			(effects
				(font
					(size 1.27 1.27)
					(thickness 0.15)
				)
				(justify left bottom)
				(hide yes)
			)
		)
		(property "Footprint" "antmicro-footprints:R_0402_1005Metric"
			(at 125.73 168.91 0)
			(effects
				(font
					(size 1.27 1.27)
					(thickness 0.15)
				)
				(justify left bottom)
				(hide yes)
			)
		)
		(property "Datasheet" "https://www.bourns.com/docs/product-datasheets/cr.pdf"
			(at 125.73 171.45 0)
			(effects
				(font
					(size 1.27 1.27)
					(thickness 0.15)
				)
				(justify left bottom)
				(hide yes)
			)
		)
		(property "Description" ""
			(at 105.41 153.67 0)
			(effects
				(font
					(size 1.27 1.27)
				)
			)
		)
		(property "Manufacturer" "Bourns"
			(at 125.73 176.53 0)
			(effects
				(font
					(size 1.27 1.27)
					(thickness 0.15)
				)
				(justify left bottom)
				(hide yes)
			)
		)
		(property "MPN" "CR0402-FX-1002GLF"
			(at 125.73 173.99 0)
			(effects
				(font
					(size 1.27 1.27)
					(thickness 0.15)
				)
				(justify left bottom)
				(hide yes)
			)
		)
		(property "Val" "10k"
			(at 107.95 151.13 0)
			(effects
				(font
					(size 1.27 1.27)
					(thickness 0.15)
				)
			)
		)
		(property "License" "Apache-2.0"
			(at 125.73 179.07 0)
			(effects
				(font
					(size 1.27 1.27)
					(thickness 0.15)
				)
				(justify left bottom)
				(hide yes)
			)
		)
		(property "Author" "Antmicro"
			(at 125.73 181.61 0)
			(effects
				(font
					(size 1.27 1.27)
					(thickness 0.15)
				)
				(justify left bottom)
				(hide yes)
			)
		)
		(property "Tolerance" "1%"
			(at 125.73 163.83 0)
			(effects
				(font
					(size 1.27 1.27)
				)
				(justify left bottom)
				(hide yes)
			)
		)
		(pin "1"
		)
		(pin "2"
		)
		(instances
			(project "sodimm-ddr5-tester"
				(path ""
					(reference "R43")
					(unit 1)
				)
			)
		)
	)
	(symbol
		(lib_id "antmicroCapacitors0402:C_18p_0402")
		(at 82.55 181.61 270)
		(unit 1)
		(exclude_from_sim no)
		(in_bom yes)
		(on_board yes)
		(dnp no)
		(property "Reference" "C111"
			(at 83.185 182.245 90)
			(effects
				(font
					(size 1.27 1.27)
				)
				(justify left)
			)
		)
		(property "Value" "C_18p_0402"
			(at 72.39 201.93 0)
			(effects
				(font
					(size 1.27 1.27)
					(thickness 0.15)
				)
				(justify left bottom)
				(hide yes)
			)
		)
		(property "Footprint" "antmicro-footprints:C_0402_1005Metric"
			(at 69.85 201.93 0)
			(effects
				(font
					(size 1.27 1.27)
					(thickness 0.15)
				)
				(justify left bottom)
				(hide yes)
			)
		)
		(property "Datasheet" "https://product.samsungsem.com/mlcc/CL05C180JB51PN.do"
			(at 67.31 201.93 0)
			(effects
				(font
					(size 1.27 1.27)
					(thickness 0.15)
				)
				(justify left bottom)
				(hide yes)
			)
		)
		(property "Description" ""
			(at 82.55 181.61 0)
			(effects
				(font
					(size 1.27 1.27)
				)
			)
		)
		(property "Manufacturer" "Samsung Electro-Mechanics"
			(at 62.23 201.93 0)
			(effects
				(font
					(size 1.27 1.27)
					(thickness 0.15)
				)
				(justify left bottom)
				(hide yes)
			)
		)
		(property "MPN" "CL05C180JB51PNC"
			(at 64.77 201.93 0)
			(effects
				(font
					(size 1.27 1.27)
					(thickness 0.15)
				)
				(justify left bottom)
				(hide yes)
			)
		)
		(property "Val" "18p"
			(at 83.185 186.055 90)
			(effects
				(font
					(size 1.27 1.27)
					(thickness 0.15)
				)
				(justify left)
			)
		)
		(property "License" "Apache-2.0"
			(at 59.69 201.93 0)
			(effects
				(font
					(size 1.27 1.27)
					(thickness 0.15)
				)
				(justify left bottom)
				(hide yes)
			)
		)
		(property "Author" "Antmicro"
			(at 57.15 201.93 0)
			(effects
				(font
					(size 1.27 1.27)
					(thickness 0.15)
				)
				(justify left bottom)
				(hide yes)
			)
		)
		(property "Voltage" ""
			(at 54.61 201.93 0)
			(effects
				(font
					(size 1.27 1.27)
				)
				(justify left bottom)
				(hide yes)
			)
		)
		(property "Dielectric" ""
			(at 52.07 201.93 0)
			(effects
				(font
					(size 1.27 1.27)
				)
				(justify left bottom)
				(hide yes)
			)
		)
		(pin "1"
		)
		(pin "2"
		)
		(instances
			(project "sodimm-ddr5-tester"
				(path ""
					(reference "C111")
					(unit 1)
				)
			)
		)
	)
	(symbol
		(lib_id "antmicroCapacitors0402:C_18p_0402")
		(at 102.87 181.61 270)
		(unit 1)
		(exclude_from_sim no)
		(in_bom yes)
		(on_board yes)
		(dnp no)
		(property "Reference" "C117"
			(at 103.505 182.245 90)
			(effects
				(font
					(size 1.27 1.27)
				)
				(justify left)
			)
		)
		(property "Value" "C_18p_0402"
			(at 92.71 201.93 0)
			(effects
				(font
					(size 1.27 1.27)
					(thickness 0.15)
				)
				(justify left bottom)
				(hide yes)
			)
		)
		(property "Footprint" "antmicro-footprints:C_0402_1005Metric"
			(at 90.17 201.93 0)
			(effects
				(font
					(size 1.27 1.27)
					(thickness 0.15)
				)
				(justify left bottom)
				(hide yes)
			)
		)
		(property "Datasheet" "https://product.samsungsem.com/mlcc/CL05C180JB51PN.do"
			(at 87.63 201.93 0)
			(effects
				(font
					(size 1.27 1.27)
					(thickness 0.15)
				)
				(justify left bottom)
				(hide yes)
			)
		)
		(property "Description" ""
			(at 102.87 181.61 0)
			(effects
				(font
					(size 1.27 1.27)
				)
			)
		)
		(property "Manufacturer" "Samsung Electro-Mechanics"
			(at 82.55 201.93 0)
			(effects
				(font
					(size 1.27 1.27)
					(thickness 0.15)
				)
				(justify left bottom)
				(hide yes)
			)
		)
		(property "MPN" "CL05C180JB51PNC"
			(at 85.09 201.93 0)
			(effects
				(font
					(size 1.27 1.27)
					(thickness 0.15)
				)
				(justify left bottom)
				(hide yes)
			)
		)
		(property "Val" "18p"
			(at 103.505 186.055 90)
			(effects
				(font
					(size 1.27 1.27)
					(thickness 0.15)
				)
				(justify left)
			)
		)
		(property "License" "Apache-2.0"
			(at 80.01 201.93 0)
			(effects
				(font
					(size 1.27 1.27)
					(thickness 0.15)
				)
				(justify left bottom)
				(hide yes)
			)
		)
		(property "Author" "Antmicro"
			(at 77.47 201.93 0)
			(effects
				(font
					(size 1.27 1.27)
					(thickness 0.15)
				)
				(justify left bottom)
				(hide yes)
			)
		)
		(property "Voltage" ""
			(at 74.93 201.93 0)
			(effects
				(font
					(size 1.27 1.27)
				)
				(justify left bottom)
				(hide yes)
			)
		)
		(property "Dielectric" ""
			(at 72.39 201.93 0)
			(effects
				(font
					(size 1.27 1.27)
				)
				(justify left bottom)
				(hide yes)
			)
		)
		(pin "1"
		)
		(pin "2"
		)
		(instances
			(project "sodimm-ddr5-tester"
				(path ""
					(reference "C117")
					(unit 1)
				)
			)
		)
	)
	(symbol
		(lib_id "antmicropower:GND")
		(at 109.22 210.185 0)
		(unit 1)
		(exclude_from_sim no)
		(in_bom yes)
		(on_board yes)
		(dnp no)
		(fields_autoplaced yes)
		(property "Reference" "#PWR0231"
			(at 109.22 216.535 0)
			(effects
				(font
					(size 1.27 1.27)
				)
				(hide yes)
			)
		)
		(property "Value" "GND"
			(at 111.76 211.455 0)
			(effects
				(font
					(size 1.27 1.27)
					(thickness 0.15)
				)
				(justify left)
			)
		)
		(property "Footprint" ""
			(at 118.11 217.805 0)
			(effects
				(font
					(size 1.27 1.27)
					(thickness 0.15)
				)
				(justify left bottom)
				(hide yes)
			)
		)
		(property "Datasheet" ""
			(at 118.11 222.885 0)
			(effects
				(font
					(size 1.27 1.27)
					(thickness 0.15)
				)
				(justify left bottom)
				(hide yes)
			)
		)
		(property "Description" ""
			(at 118.11 225.425 0)
			(effects
				(font
					(size 1.27 1.27)
				)
				(justify left bottom)
				(hide yes)
			)
		)
		(property "Author" "Antmicro"
			(at 118.11 217.805 0)
			(effects
				(font
					(size 1.27 1.27)
					(thickness 0.15)
				)
				(justify left bottom)
				(hide yes)
			)
		)
		(property "License" "Apache-2.0"
			(at 118.11 220.345 0)
			(effects
				(font
					(size 1.27 1.27)
					(thickness 0.15)
				)
				(justify left bottom)
				(hide yes)
			)
		)
		(pin "1"
		)
		(instances
			(project "sodimm-ddr5-tester"
				(path ""
					(reference "#PWR0231")
					(unit 1)
				)
			)
		)
	)
	(symbol
		(lib_id "antmicropower:GND")
		(at 102.87 186.69 0)
		(unit 1)
		(exclude_from_sim no)
		(in_bom yes)
		(on_board yes)
		(dnp no)
		(fields_autoplaced yes)
		(property "Reference" "#PWR0232"
			(at 102.87 193.04 0)
			(effects
				(font
					(size 1.27 1.27)
				)
				(hide yes)
			)
		)
		(property "Value" "GND"
			(at 105.41 187.96 0)
			(effects
				(font
					(size 1.27 1.27)
					(thickness 0.15)
				)
				(justify left)
			)
		)
		(property "Footprint" ""
			(at 111.76 194.31 0)
			(effects
				(font
					(size 1.27 1.27)
					(thickness 0.15)
				)
				(justify left bottom)
				(hide yes)
			)
		)
		(property "Datasheet" ""
			(at 111.76 199.39 0)
			(effects
				(font
					(size 1.27 1.27)
					(thickness 0.15)
				)
				(justify left bottom)
				(hide yes)
			)
		)
		(property "Description" ""
			(at 111.76 201.93 0)
			(effects
				(font
					(size 1.27 1.27)
				)
				(justify left bottom)
				(hide yes)
			)
		)
		(property "Author" "Antmicro"
			(at 111.76 194.31 0)
			(effects
				(font
					(size 1.27 1.27)
					(thickness 0.15)
				)
				(justify left bottom)
				(hide yes)
			)
		)
		(property "License" "Apache-2.0"
			(at 111.76 196.85 0)
			(effects
				(font
					(size 1.27 1.27)
					(thickness 0.15)
				)
				(justify left bottom)
				(hide yes)
			)
		)
		(pin "1"
		)
		(instances
			(project "sodimm-ddr5-tester"
				(path ""
					(reference "#PWR0232")
					(unit 1)
				)
			)
		)
	)
	(symbol
		(lib_id "antmicropower:GND")
		(at 82.55 186.69 0)
		(unit 1)
		(exclude_from_sim no)
		(in_bom yes)
		(on_board yes)
		(dnp no)
		(fields_autoplaced yes)
		(property "Reference" "#PWR0235"
			(at 82.55 193.04 0)
			(effects
				(font
					(size 1.27 1.27)
				)
				(hide yes)
			)
		)
		(property "Value" "GND"
			(at 85.09 187.96 0)
			(effects
				(font
					(size 1.27 1.27)
					(thickness 0.15)
				)
				(justify left)
			)
		)
		(property "Footprint" ""
			(at 91.44 194.31 0)
			(effects
				(font
					(size 1.27 1.27)
					(thickness 0.15)
				)
				(justify left bottom)
				(hide yes)
			)
		)
		(property "Datasheet" ""
			(at 91.44 199.39 0)
			(effects
				(font
					(size 1.27 1.27)
					(thickness 0.15)
				)
				(justify left bottom)
				(hide yes)
			)
		)
		(property "Description" ""
			(at 91.44 201.93 0)
			(effects
				(font
					(size 1.27 1.27)
				)
				(justify left bottom)
				(hide yes)
			)
		)
		(property "Author" "Antmicro"
			(at 91.44 194.31 0)
			(effects
				(font
					(size 1.27 1.27)
					(thickness 0.15)
				)
				(justify left bottom)
				(hide yes)
			)
		)
		(property "License" "Apache-2.0"
			(at 91.44 196.85 0)
			(effects
				(font
					(size 1.27 1.27)
					(thickness 0.15)
				)
				(justify left bottom)
				(hide yes)
			)
		)
		(pin "1"
		)
		(instances
			(project "sodimm-ddr5-tester"
				(path ""
					(reference "#PWR0235")
					(unit 1)
				)
			)
		)
	)
	(symbol
		(lib_id "antmicroCapacitors0402:C_100n_0402")
		(at 48.387 120.015 270)
		(unit 1)
		(exclude_from_sim no)
		(in_bom yes)
		(on_board yes)
		(dnp no)
		(property "Reference" "C115"
			(at 49.022 120.65 90)
			(effects
				(font
					(size 1.27 1.27)
				)
				(justify left)
			)
		)
		(property "Value" "C_100n_0402"
			(at 38.227 140.335 0)
			(effects
				(font
					(size 1.27 1.27)
					(thickness 0.15)
				)
				(justify left bottom)
				(hide yes)
			)
		)
		(property "Footprint" "antmicro-footprints:C_0402_1005Metric"
			(at 35.687 140.335 0)
			(effects
				(font
					(size 1.27 1.27)
					(thickness 0.15)
				)
				(justify left bottom)
				(hide yes)
			)
		)
		(property "Datasheet" "https://www.murata.com/products/productdetail?partno=GRM155R61H104KE14%23"
			(at 33.147 140.335 0)
			(effects
				(font
					(size 1.27 1.27)
					(thickness 0.15)
				)
				(justify left bottom)
				(hide yes)
			)
		)
		(property "Description" ""
			(at 48.387 120.015 0)
			(effects
				(font
					(size 1.27 1.27)
				)
			)
		)
		(property "Manufacturer" "Murata"
			(at 28.067 140.335 0)
			(effects
				(font
					(size 1.27 1.27)
					(thickness 0.15)
				)
				(justify left bottom)
				(hide yes)
			)
		)
		(property "MPN" "GRM155R61H104KE14D"
			(at 30.607 140.335 0)
			(effects
				(font
					(size 1.27 1.27)
					(thickness 0.15)
				)
				(justify left bottom)
				(hide yes)
			)
		)
		(property "Val" "100n"
			(at 49.022 124.46 90)
			(effects
				(font
					(size 1.27 1.27)
					(thickness 0.15)
				)
				(justify left)
			)
		)
		(property "License" "Apache-2.0"
			(at 25.527 140.335 0)
			(effects
				(font
					(size 1.27 1.27)
					(thickness 0.15)
				)
				(justify left bottom)
				(hide yes)
			)
		)
		(property "Author" "Antmicro"
			(at 22.987 140.335 0)
			(effects
				(font
					(size 1.27 1.27)
					(thickness 0.15)
				)
				(justify left bottom)
				(hide yes)
			)
		)
		(property "Voltage" "50V"
			(at 20.447 140.335 0)
			(effects
				(font
					(size 1.27 1.27)
				)
				(justify left bottom)
				(hide yes)
			)
		)
		(property "Dielectric" "X5R"
			(at 17.907 140.335 0)
			(effects
				(font
					(size 1.27 1.27)
				)
				(justify left bottom)
				(hide yes)
			)
		)
		(pin "1"
		)
		(pin "2"
		)
		(instances
			(project "sodimm-ddr5-tester"
				(path ""
					(reference "C115")
					(unit 1)
				)
			)
		)
	)
	(symbol
		(lib_id "antmicroCapacitors0402:C_100n_0402")
		(at 56.007 120.015 270)
		(unit 1)
		(exclude_from_sim no)
		(in_bom yes)
		(on_board yes)
		(dnp no)
		(property "Reference" "C118"
			(at 56.642 120.6501 90)
			(effects
				(font
					(size 1.27 1.27)
				)
				(justify left)
			)
		)
		(property "Value" "C_100n_0402"
			(at 45.847 140.335 0)
			(effects
				(font
					(size 1.27 1.27)
					(thickness 0.15)
				)
				(justify left bottom)
				(hide yes)
			)
		)
		(property "Footprint" "antmicro-footprints:C_0402_1005Metric"
			(at 43.307 140.335 0)
			(effects
				(font
					(size 1.27 1.27)
					(thickness 0.15)
				)
				(justify left bottom)
				(hide yes)
			)
		)
		(property "Datasheet" "https://www.murata.com/products/productdetail?partno=GRM155R61H104KE14%23"
			(at 40.767 140.335 0)
			(effects
				(font
					(size 1.27 1.27)
					(thickness 0.15)
				)
				(justify left bottom)
				(hide yes)
			)
		)
		(property "Description" ""
			(at 56.007 120.015 0)
			(effects
				(font
					(size 1.27 1.27)
				)
			)
		)
		(property "Manufacturer" "Murata"
			(at 35.687 140.335 0)
			(effects
				(font
					(size 1.27 1.27)
					(thickness 0.15)
				)
				(justify left bottom)
				(hide yes)
			)
		)
		(property "MPN" "GRM155R61H104KE14D"
			(at 38.227 140.335 0)
			(effects
				(font
					(size 1.27 1.27)
					(thickness 0.15)
				)
				(justify left bottom)
				(hide yes)
			)
		)
		(property "Val" "100n"
			(at 56.642 124.46 90)
			(effects
				(font
					(size 1.27 1.27)
					(thickness 0.15)
				)
				(justify left)
			)
		)
		(property "License" "Apache-2.0"
			(at 33.147 140.335 0)
			(effects
				(font
					(size 1.27 1.27)
					(thickness 0.15)
				)
				(justify left bottom)
				(hide yes)
			)
		)
		(property "Author" "Antmicro"
			(at 30.607 140.335 0)
			(effects
				(font
					(size 1.27 1.27)
					(thickness 0.15)
				)
				(justify left bottom)
				(hide yes)
			)
		)
		(property "Voltage" "50V"
			(at 28.067 140.335 0)
			(effects
				(font
					(size 1.27 1.27)
				)
				(justify left bottom)
				(hide yes)
			)
		)
		(property "Dielectric" "X5R"
			(at 25.527 140.335 0)
			(effects
				(font
					(size 1.27 1.27)
				)
				(justify left bottom)
				(hide yes)
			)
		)
		(pin "1"
		)
		(pin "2"
		)
		(instances
			(project "sodimm-ddr5-tester"
				(path ""
					(reference "C118")
					(unit 1)
				)
			)
		)
	)
	(symbol
		(lib_id "antmicroCapacitors0402:C_100n_0402")
		(at 63.627 120.015 270)
		(unit 1)
		(exclude_from_sim no)
		(in_bom yes)
		(on_board yes)
		(dnp no)
		(property "Reference" "C119"
			(at 64.262 120.6501 90)
			(effects
				(font
					(size 1.27 1.27)
				)
				(justify left)
			)
		)
		(property "Value" "C_100n_0402"
			(at 53.467 140.335 0)
			(effects
				(font
					(size 1.27 1.27)
					(thickness 0.15)
				)
				(justify left bottom)
				(hide yes)
			)
		)
		(property "Footprint" "antmicro-footprints:C_0402_1005Metric"
			(at 50.927 140.335 0)
			(effects
				(font
					(size 1.27 1.27)
					(thickness 0.15)
				)
				(justify left bottom)
				(hide yes)
			)
		)
		(property "Datasheet" "https://www.murata.com/products/productdetail?partno=GRM155R61H104KE14%23"
			(at 48.387 140.335 0)
			(effects
				(font
					(size 1.27 1.27)
					(thickness 0.15)
				)
				(justify left bottom)
				(hide yes)
			)
		)
		(property "Description" ""
			(at 63.627 120.015 0)
			(effects
				(font
					(size 1.27 1.27)
				)
			)
		)
		(property "Manufacturer" "Murata"
			(at 43.307 140.335 0)
			(effects
				(font
					(size 1.27 1.27)
					(thickness 0.15)
				)
				(justify left bottom)
				(hide yes)
			)
		)
		(property "MPN" "GRM155R61H104KE14D"
			(at 45.847 140.335 0)
			(effects
				(font
					(size 1.27 1.27)
					(thickness 0.15)
				)
				(justify left bottom)
				(hide yes)
			)
		)
		(property "Val" "100n"
			(at 64.262 124.46 90)
			(effects
				(font
					(size 1.27 1.27)
					(thickness 0.15)
				)
				(justify left)
			)
		)
		(property "License" "Apache-2.0"
			(at 40.767 140.335 0)
			(effects
				(font
					(size 1.27 1.27)
					(thickness 0.15)
				)
				(justify left bottom)
				(hide yes)
			)
		)
		(property "Author" "Antmicro"
			(at 38.227 140.335 0)
			(effects
				(font
					(size 1.27 1.27)
					(thickness 0.15)
				)
				(justify left bottom)
				(hide yes)
			)
		)
		(property "Voltage" "50V"
			(at 35.687 140.335 0)
			(effects
				(font
					(size 1.27 1.27)
				)
				(justify left bottom)
				(hide yes)
			)
		)
		(property "Dielectric" "X5R"
			(at 33.147 140.335 0)
			(effects
				(font
					(size 1.27 1.27)
				)
				(justify left bottom)
				(hide yes)
			)
		)
		(pin "1"
		)
		(pin "2"
		)
		(instances
			(project "sodimm-ddr5-tester"
				(path ""
					(reference "C119")
					(unit 1)
				)
			)
		)
	)
	(symbol
		(lib_id "antmicroCapacitors0402:C_100n_0402")
		(at 71.247 120.015 270)
		(unit 1)
		(exclude_from_sim no)
		(in_bom yes)
		(on_board yes)
		(dnp no)
		(property "Reference" "C120"
			(at 71.882 120.6501 90)
			(effects
				(font
					(size 1.27 1.27)
				)
				(justify left)
			)
		)
		(property "Value" "C_100n_0402"
			(at 61.087 140.335 0)
			(effects
				(font
					(size 1.27 1.27)
					(thickness 0.15)
				)
				(justify left bottom)
				(hide yes)
			)
		)
		(property "Footprint" "antmicro-footprints:C_0402_1005Metric"
			(at 58.547 140.335 0)
			(effects
				(font
					(size 1.27 1.27)
					(thickness 0.15)
				)
				(justify left bottom)
				(hide yes)
			)
		)
		(property "Datasheet" "https://www.murata.com/products/productdetail?partno=GRM155R61H104KE14%23"
			(at 56.007 140.335 0)
			(effects
				(font
					(size 1.27 1.27)
					(thickness 0.15)
				)
				(justify left bottom)
				(hide yes)
			)
		)
		(property "Description" ""
			(at 71.247 120.015 0)
			(effects
				(font
					(size 1.27 1.27)
				)
			)
		)
		(property "Manufacturer" "Murata"
			(at 50.927 140.335 0)
			(effects
				(font
					(size 1.27 1.27)
					(thickness 0.15)
				)
				(justify left bottom)
				(hide yes)
			)
		)
		(property "MPN" "GRM155R61H104KE14D"
			(at 53.467 140.335 0)
			(effects
				(font
					(size 1.27 1.27)
					(thickness 0.15)
				)
				(justify left bottom)
				(hide yes)
			)
		)
		(property "Val" "100n"
			(at 71.882 124.46 90)
			(effects
				(font
					(size 1.27 1.27)
					(thickness 0.15)
				)
				(justify left)
			)
		)
		(property "License" "Apache-2.0"
			(at 48.387 140.335 0)
			(effects
				(font
					(size 1.27 1.27)
					(thickness 0.15)
				)
				(justify left bottom)
				(hide yes)
			)
		)
		(property "Author" "Antmicro"
			(at 45.847 140.335 0)
			(effects
				(font
					(size 1.27 1.27)
					(thickness 0.15)
				)
				(justify left bottom)
				(hide yes)
			)
		)
		(property "Voltage" "50V"
			(at 43.307 140.335 0)
			(effects
				(font
					(size 1.27 1.27)
				)
				(justify left bottom)
				(hide yes)
			)
		)
		(property "Dielectric" "X5R"
			(at 40.767 140.335 0)
			(effects
				(font
					(size 1.27 1.27)
				)
				(justify left bottom)
				(hide yes)
			)
		)
		(pin "1"
		)
		(pin "2"
		)
		(instances
			(project "sodimm-ddr5-tester"
				(path ""
					(reference "C120")
					(unit 1)
				)
			)
		)
	)
	(symbol
		(lib_id "antmicropower:GND")
		(at 48.387 125.095 0)
		(unit 1)
		(exclude_from_sim no)
		(in_bom yes)
		(on_board yes)
		(dnp no)
		(fields_autoplaced yes)
		(property "Reference" "#PWR0347"
			(at 48.387 131.445 0)
			(effects
				(font
					(size 1.27 1.27)
				)
				(hide yes)
			)
		)
		(property "Value" "GND"
			(at 50.8 126.365 0)
			(effects
				(font
					(size 1.27 1.27)
					(thickness 0.15)
				)
				(justify left)
			)
		)
		(property "Footprint" ""
			(at 57.277 132.715 0)
			(effects
				(font
					(size 1.27 1.27)
					(thickness 0.15)
				)
				(justify left bottom)
				(hide yes)
			)
		)
		(property "Datasheet" ""
			(at 57.277 137.795 0)
			(effects
				(font
					(size 1.27 1.27)
					(thickness 0.15)
				)
				(justify left bottom)
				(hide yes)
			)
		)
		(property "Description" ""
			(at 57.277 140.335 0)
			(effects
				(font
					(size 1.27 1.27)
				)
				(justify left bottom)
				(hide yes)
			)
		)
		(property "Author" "Antmicro"
			(at 57.277 132.715 0)
			(effects
				(font
					(size 1.27 1.27)
					(thickness 0.15)
				)
				(justify left bottom)
				(hide yes)
			)
		)
		(property "License" "Apache-2.0"
			(at 57.277 135.255 0)
			(effects
				(font
					(size 1.27 1.27)
					(thickness 0.15)
				)
				(justify left bottom)
				(hide yes)
			)
		)
		(pin "1"
		)
		(instances
			(project "sodimm-ddr5-tester"
				(path ""
					(reference "#PWR0347")
					(unit 1)
				)
			)
		)
	)
	(symbol
		(lib_id "antmicropower:GND")
		(at 56.007 125.095 0)
		(unit 1)
		(exclude_from_sim no)
		(in_bom yes)
		(on_board yes)
		(dnp no)
		(fields_autoplaced yes)
		(property "Reference" "#PWR0348"
			(at 56.007 131.445 0)
			(effects
				(font
					(size 1.27 1.27)
				)
				(hide yes)
			)
		)
		(property "Value" "GND"
			(at 58.42 126.365 0)
			(effects
				(font
					(size 1.27 1.27)
					(thickness 0.15)
				)
				(justify left)
			)
		)
		(property "Footprint" ""
			(at 64.897 132.715 0)
			(effects
				(font
					(size 1.27 1.27)
					(thickness 0.15)
				)
				(justify left bottom)
				(hide yes)
			)
		)
		(property "Datasheet" ""
			(at 64.897 137.795 0)
			(effects
				(font
					(size 1.27 1.27)
					(thickness 0.15)
				)
				(justify left bottom)
				(hide yes)
			)
		)
		(property "Description" ""
			(at 64.897 140.335 0)
			(effects
				(font
					(size 1.27 1.27)
				)
				(justify left bottom)
				(hide yes)
			)
		)
		(property "Author" "Antmicro"
			(at 64.897 132.715 0)
			(effects
				(font
					(size 1.27 1.27)
					(thickness 0.15)
				)
				(justify left bottom)
				(hide yes)
			)
		)
		(property "License" "Apache-2.0"
			(at 64.897 135.255 0)
			(effects
				(font
					(size 1.27 1.27)
					(thickness 0.15)
				)
				(justify left bottom)
				(hide yes)
			)
		)
		(pin "1"
		)
		(instances
			(project "sodimm-ddr5-tester"
				(path ""
					(reference "#PWR0348")
					(unit 1)
				)
			)
		)
	)
	(symbol
		(lib_id "antmicropower:GND")
		(at 63.627 125.095 0)
		(unit 1)
		(exclude_from_sim no)
		(in_bom yes)
		(on_board yes)
		(dnp no)
		(fields_autoplaced yes)
		(property "Reference" "#PWR0260"
			(at 63.627 131.445 0)
			(effects
				(font
					(size 1.27 1.27)
				)
				(hide yes)
			)
		)
		(property "Value" "GND"
			(at 66.04 126.365 0)
			(effects
				(font
					(size 1.27 1.27)
					(thickness 0.15)
				)
				(justify left)
			)
		)
		(property "Footprint" ""
			(at 72.517 132.715 0)
			(effects
				(font
					(size 1.27 1.27)
					(thickness 0.15)
				)
				(justify left bottom)
				(hide yes)
			)
		)
		(property "Datasheet" ""
			(at 72.517 137.795 0)
			(effects
				(font
					(size 1.27 1.27)
					(thickness 0.15)
				)
				(justify left bottom)
				(hide yes)
			)
		)
		(property "Description" ""
			(at 72.517 140.335 0)
			(effects
				(font
					(size 1.27 1.27)
				)
				(justify left bottom)
				(hide yes)
			)
		)
		(property "Author" "Antmicro"
			(at 72.517 132.715 0)
			(effects
				(font
					(size 1.27 1.27)
					(thickness 0.15)
				)
				(justify left bottom)
				(hide yes)
			)
		)
		(property "License" "Apache-2.0"
			(at 72.517 135.255 0)
			(effects
				(font
					(size 1.27 1.27)
					(thickness 0.15)
				)
				(justify left bottom)
				(hide yes)
			)
		)
		(pin "1"
		)
		(instances
			(project "sodimm-ddr5-tester"
				(path ""
					(reference "#PWR0260")
					(unit 1)
				)
			)
		)
	)
	(symbol
		(lib_id "antmicropower:GND")
		(at 71.247 125.095 0)
		(unit 1)
		(exclude_from_sim no)
		(in_bom yes)
		(on_board yes)
		(dnp no)
		(fields_autoplaced yes)
		(property "Reference" "#PWR0334"
			(at 71.247 131.445 0)
			(effects
				(font
					(size 1.27 1.27)
				)
				(hide yes)
			)
		)
		(property "Value" "GND"
			(at 73.66 126.365 0)
			(effects
				(font
					(size 1.27 1.27)
					(thickness 0.15)
				)
				(justify left)
			)
		)
		(property "Footprint" ""
			(at 80.137 132.715 0)
			(effects
				(font
					(size 1.27 1.27)
					(thickness 0.15)
				)
				(justify left bottom)
				(hide yes)
			)
		)
		(property "Datasheet" ""
			(at 80.137 137.795 0)
			(effects
				(font
					(size 1.27 1.27)
					(thickness 0.15)
				)
				(justify left bottom)
				(hide yes)
			)
		)
		(property "Description" ""
			(at 80.137 140.335 0)
			(effects
				(font
					(size 1.27 1.27)
				)
				(justify left bottom)
				(hide yes)
			)
		)
		(property "Author" "Antmicro"
			(at 80.137 132.715 0)
			(effects
				(font
					(size 1.27 1.27)
					(thickness 0.15)
				)
				(justify left bottom)
				(hide yes)
			)
		)
		(property "License" "Apache-2.0"
			(at 80.137 135.255 0)
			(effects
				(font
					(size 1.27 1.27)
					(thickness 0.15)
				)
				(justify left bottom)
				(hide yes)
			)
		)
		(pin "1"
		)
		(instances
			(project "sodimm-ddr5-tester"
				(path ""
					(reference "#PWR0334")
					(unit 1)
				)
			)
		)
	)
	(symbol
		(lib_id "antmicroCapacitors0402:C_100n_0402")
		(at 59.055 177.8 270)
		(unit 1)
		(exclude_from_sim no)
		(in_bom yes)
		(on_board yes)
		(dnp no)
		(property "Reference" "C123"
			(at 59.69 178.435 90)
			(effects
				(font
					(size 1.27 1.27)
				)
				(justify left)
			)
		)
		(property "Value" "C_100n_0402"
			(at 48.895 198.12 0)
			(effects
				(font
					(size 1.27 1.27)
					(thickness 0.15)
				)
				(justify left bottom)
				(hide yes)
			)
		)
		(property "Footprint" "antmicro-footprints:C_0402_1005Metric"
			(at 46.355 198.12 0)
			(effects
				(font
					(size 1.27 1.27)
					(thickness 0.15)
				)
				(justify left bottom)
				(hide yes)
			)
		)
		(property "Datasheet" "https://www.murata.com/products/productdetail?partno=GRM155R61H104KE14%23"
			(at 43.815 198.12 0)
			(effects
				(font
					(size 1.27 1.27)
					(thickness 0.15)
				)
				(justify left bottom)
				(hide yes)
			)
		)
		(property "Description" ""
			(at 59.055 177.8 0)
			(effects
				(font
					(size 1.27 1.27)
				)
			)
		)
		(property "Manufacturer" "Murata"
			(at 38.735 198.12 0)
			(effects
				(font
					(size 1.27 1.27)
					(thickness 0.15)
				)
				(justify left bottom)
				(hide yes)
			)
		)
		(property "MPN" "GRM155R61H104KE14D"
			(at 41.275 198.12 0)
			(effects
				(font
					(size 1.27 1.27)
					(thickness 0.15)
				)
				(justify left bottom)
				(hide yes)
			)
		)
		(property "Val" "100n"
			(at 59.69 182.245 90)
			(effects
				(font
					(size 1.27 1.27)
					(thickness 0.15)
				)
				(justify left)
			)
		)
		(property "License" "Apache-2.0"
			(at 36.195 198.12 0)
			(effects
				(font
					(size 1.27 1.27)
					(thickness 0.15)
				)
				(justify left bottom)
				(hide yes)
			)
		)
		(property "Author" "Antmicro"
			(at 33.655 198.12 0)
			(effects
				(font
					(size 1.27 1.27)
					(thickness 0.15)
				)
				(justify left bottom)
				(hide yes)
			)
		)
		(property "Voltage" "50V"
			(at 31.115 198.12 0)
			(effects
				(font
					(size 1.27 1.27)
				)
				(justify left bottom)
				(hide yes)
			)
		)
		(property "Dielectric" "X5R"
			(at 28.575 198.12 0)
			(effects
				(font
					(size 1.27 1.27)
				)
				(justify left bottom)
				(hide yes)
			)
		)
		(pin "1"
		)
		(pin "2"
		)
		(instances
			(project "sodimm-ddr5-tester"
				(path ""
					(reference "C123")
					(unit 1)
				)
			)
		)
	)
	(symbol
		(lib_id "antmicroCapacitors0402:C_100n_0402")
		(at 66.675 177.8 270)
		(unit 1)
		(exclude_from_sim no)
		(in_bom yes)
		(on_board yes)
		(dnp no)
		(property "Reference" "C125"
			(at 67.31 178.435 90)
			(effects
				(font
					(size 1.27 1.27)
				)
				(justify left)
			)
		)
		(property "Value" "C_100n_0402"
			(at 56.515 198.12 0)
			(effects
				(font
					(size 1.27 1.27)
					(thickness 0.15)
				)
				(justify left bottom)
				(hide yes)
			)
		)
		(property "Footprint" "antmicro-footprints:C_0402_1005Metric"
			(at 53.975 198.12 0)
			(effects
				(font
					(size 1.27 1.27)
					(thickness 0.15)
				)
				(justify left bottom)
				(hide yes)
			)
		)
		(property "Datasheet" "https://www.murata.com/products/productdetail?partno=GRM155R61H104KE14%23"
			(at 51.435 198.12 0)
			(effects
				(font
					(size 1.27 1.27)
					(thickness 0.15)
				)
				(justify left bottom)
				(hide yes)
			)
		)
		(property "Description" ""
			(at 66.675 177.8 0)
			(effects
				(font
					(size 1.27 1.27)
				)
			)
		)
		(property "Manufacturer" "Murata"
			(at 46.355 198.12 0)
			(effects
				(font
					(size 1.27 1.27)
					(thickness 0.15)
				)
				(justify left bottom)
				(hide yes)
			)
		)
		(property "MPN" "GRM155R61H104KE14D"
			(at 48.895 198.12 0)
			(effects
				(font
					(size 1.27 1.27)
					(thickness 0.15)
				)
				(justify left bottom)
				(hide yes)
			)
		)
		(property "Val" "100n"
			(at 67.31 182.245 90)
			(effects
				(font
					(size 1.27 1.27)
					(thickness 0.15)
				)
				(justify left)
			)
		)
		(property "License" "Apache-2.0"
			(at 43.815 198.12 0)
			(effects
				(font
					(size 1.27 1.27)
					(thickness 0.15)
				)
				(justify left bottom)
				(hide yes)
			)
		)
		(property "Author" "Antmicro"
			(at 41.275 198.12 0)
			(effects
				(font
					(size 1.27 1.27)
					(thickness 0.15)
				)
				(justify left bottom)
				(hide yes)
			)
		)
		(property "Voltage" "50V"
			(at 38.735 198.12 0)
			(effects
				(font
					(size 1.27 1.27)
				)
				(justify left bottom)
				(hide yes)
			)
		)
		(property "Dielectric" "X5R"
			(at 36.195 198.12 0)
			(effects
				(font
					(size 1.27 1.27)
				)
				(justify left bottom)
				(hide yes)
			)
		)
		(pin "1"
		)
		(pin "2"
		)
		(instances
			(project "sodimm-ddr5-tester"
				(path ""
					(reference "C125")
					(unit 1)
				)
			)
		)
	)
	(symbol
		(lib_id "antmicropower:GND")
		(at 59.055 182.88 0)
		(unit 1)
		(exclude_from_sim no)
		(in_bom yes)
		(on_board yes)
		(dnp no)
		(fields_autoplaced yes)
		(property "Reference" "#PWR0239"
			(at 59.055 189.23 0)
			(effects
				(font
					(size 1.27 1.27)
				)
				(hide yes)
			)
		)
		(property "Value" "GND"
			(at 60.96 184.15 0)
			(effects
				(font
					(size 1.27 1.27)
					(thickness 0.15)
				)
				(justify left)
			)
		)
		(property "Footprint" ""
			(at 67.945 190.5 0)
			(effects
				(font
					(size 1.27 1.27)
					(thickness 0.15)
				)
				(justify left bottom)
				(hide yes)
			)
		)
		(property "Datasheet" ""
			(at 67.945 195.58 0)
			(effects
				(font
					(size 1.27 1.27)
					(thickness 0.15)
				)
				(justify left bottom)
				(hide yes)
			)
		)
		(property "Description" ""
			(at 67.945 198.12 0)
			(effects
				(font
					(size 1.27 1.27)
				)
				(justify left bottom)
				(hide yes)
			)
		)
		(property "Author" "Antmicro"
			(at 67.945 190.5 0)
			(effects
				(font
					(size 1.27 1.27)
					(thickness 0.15)
				)
				(justify left bottom)
				(hide yes)
			)
		)
		(property "License" "Apache-2.0"
			(at 67.945 193.04 0)
			(effects
				(font
					(size 1.27 1.27)
					(thickness 0.15)
				)
				(justify left bottom)
				(hide yes)
			)
		)
		(pin "1"
		)
		(instances
			(project "sodimm-ddr5-tester"
				(path ""
					(reference "#PWR0239")
					(unit 1)
				)
			)
		)
	)
	(symbol
		(lib_id "antmicropower:GND")
		(at 66.675 182.88 0)
		(unit 1)
		(exclude_from_sim no)
		(in_bom yes)
		(on_board yes)
		(dnp no)
		(fields_autoplaced yes)
		(property "Reference" "#PWR0246"
			(at 66.675 189.23 0)
			(effects
				(font
					(size 1.27 1.27)
				)
				(hide yes)
			)
		)
		(property "Value" "GND"
			(at 68.58 184.15 0)
			(effects
				(font
					(size 1.27 1.27)
					(thickness 0.15)
				)
				(justify left)
			)
		)
		(property "Footprint" ""
			(at 75.565 190.5 0)
			(effects
				(font
					(size 1.27 1.27)
					(thickness 0.15)
				)
				(justify left bottom)
				(hide yes)
			)
		)
		(property "Datasheet" ""
			(at 75.565 195.58 0)
			(effects
				(font
					(size 1.27 1.27)
					(thickness 0.15)
				)
				(justify left bottom)
				(hide yes)
			)
		)
		(property "Description" ""
			(at 75.565 198.12 0)
			(effects
				(font
					(size 1.27 1.27)
				)
				(justify left bottom)
				(hide yes)
			)
		)
		(property "Author" "Antmicro"
			(at 75.565 190.5 0)
			(effects
				(font
					(size 1.27 1.27)
					(thickness 0.15)
				)
				(justify left bottom)
				(hide yes)
			)
		)
		(property "License" "Apache-2.0"
			(at 75.565 193.04 0)
			(effects
				(font
					(size 1.27 1.27)
					(thickness 0.15)
				)
				(justify left bottom)
				(hide yes)
			)
		)
		(pin "1"
		)
		(instances
			(project "sodimm-ddr5-tester"
				(path ""
					(reference "#PWR0246")
					(unit 1)
				)
			)
		)
	)
	(symbol
		(lib_id "antmicroCapacitors0402:C_4u7_0402")
		(at 51.435 177.8 270)
		(unit 1)
		(exclude_from_sim no)
		(in_bom yes)
		(on_board yes)
		(dnp no)
		(property "Reference" "C122"
			(at 52.07 178.435 90)
			(effects
				(font
					(size 1.27 1.27)
				)
				(justify left)
			)
		)
		(property "Value" "C_4u7_0402"
			(at 41.275 198.12 0)
			(effects
				(font
					(size 1.27 1.27)
					(thickness 0.15)
				)
				(justify left bottom)
				(hide yes)
			)
		)
		(property "Footprint" "antmicro-footprints:C_0402_1005Metric"
			(at 38.735 198.12 0)
			(effects
				(font
					(size 1.27 1.27)
					(thickness 0.15)
				)
				(justify left bottom)
				(hide yes)
			)
		)
		(property "Datasheet" "https://www.murata.com/products/productdetail?partno=GRM155R61A475MEAA%23"
			(at 36.195 198.12 0)
			(effects
				(font
					(size 1.27 1.27)
					(thickness 0.15)
				)
				(justify left bottom)
				(hide yes)
			)
		)
		(property "Description" ""
			(at 51.435 177.8 0)
			(effects
				(font
					(size 1.27 1.27)
				)
			)
		)
		(property "Manufacturer" "Murata"
			(at 31.115 198.12 0)
			(effects
				(font
					(size 1.27 1.27)
					(thickness 0.15)
				)
				(justify left bottom)
				(hide yes)
			)
		)
		(property "MPN" "GRM155R61A475MEAAD"
			(at 33.655 198.12 0)
			(effects
				(font
					(size 1.27 1.27)
					(thickness 0.15)
				)
				(justify left bottom)
				(hide yes)
			)
		)
		(property "Val" "4u7"
			(at 52.07 182.245 90)
			(effects
				(font
					(size 1.27 1.27)
					(thickness 0.15)
				)
				(justify left)
			)
		)
		(property "License" "Apache-2.0"
			(at 28.575 198.12 0)
			(effects
				(font
					(size 1.27 1.27)
					(thickness 0.15)
				)
				(justify left bottom)
				(hide yes)
			)
		)
		(property "Author" "Antmicro"
			(at 26.035 198.12 0)
			(effects
				(font
					(size 1.27 1.27)
					(thickness 0.15)
				)
				(justify left bottom)
				(hide yes)
			)
		)
		(property "Voltage" ""
			(at 23.495 198.12 0)
			(effects
				(font
					(size 1.27 1.27)
				)
				(justify left bottom)
				(hide yes)
			)
		)
		(property "Dielectric" ""
			(at 20.955 198.12 0)
			(effects
				(font
					(size 1.27 1.27)
				)
				(justify left bottom)
				(hide yes)
			)
		)
		(pin "1"
		)
		(pin "2"
		)
		(instances
			(project "sodimm-ddr5-tester"
				(path ""
					(reference "C122")
					(unit 1)
				)
			)
		)
	)
	(symbol
		(lib_id "antmicropower:GND")
		(at 51.435 182.88 0)
		(unit 1)
		(exclude_from_sim no)
		(in_bom yes)
		(on_board yes)
		(dnp no)
		(fields_autoplaced yes)
		(property "Reference" "#PWR0229"
			(at 51.435 189.23 0)
			(effects
				(font
					(size 1.27 1.27)
				)
				(hide yes)
			)
		)
		(property "Value" "GND"
			(at 53.34 184.15 0)
			(effects
				(font
					(size 1.27 1.27)
					(thickness 0.15)
				)
				(justify left)
			)
		)
		(property "Footprint" ""
			(at 60.325 190.5 0)
			(effects
				(font
					(size 1.27 1.27)
					(thickness 0.15)
				)
				(justify left bottom)
				(hide yes)
			)
		)
		(property "Datasheet" ""
			(at 60.325 195.58 0)
			(effects
				(font
					(size 1.27 1.27)
					(thickness 0.15)
				)
				(justify left bottom)
				(hide yes)
			)
		)
		(property "Description" ""
			(at 60.325 198.12 0)
			(effects
				(font
					(size 1.27 1.27)
				)
				(justify left bottom)
				(hide yes)
			)
		)
		(property "Author" "Antmicro"
			(at 60.325 190.5 0)
			(effects
				(font
					(size 1.27 1.27)
					(thickness 0.15)
				)
				(justify left bottom)
				(hide yes)
			)
		)
		(property "License" "Apache-2.0"
			(at 60.325 193.04 0)
			(effects
				(font
					(size 1.27 1.27)
					(thickness 0.15)
				)
				(justify left bottom)
				(hide yes)
			)
		)
		(pin "1"
		)
		(instances
			(project "sodimm-ddr5-tester"
				(path ""
					(reference "#PWR0229")
					(unit 1)
				)
			)
		)
	)
	(symbol
		(lib_id "antmicroResistors0402:R_22R_0402")
		(at 272.415 107.315 0)
		(unit 1)
		(exclude_from_sim no)
		(in_bom yes)
		(on_board yes)
		(dnp no)
		(property "Reference" "R47"
			(at 270.51 106.045 0)
			(effects
				(font
					(size 1.27 1.27)
				)
			)
		)
		(property "Value" "R_22R_0402"
			(at 292.735 120.015 0)
			(effects
				(font
					(size 1.27 1.27)
					(thickness 0.15)
				)
				(justify left bottom)
				(hide yes)
			)
		)
		(property "Footprint" "antmicro-footprints:R_0402_1005Metric"
			(at 292.735 122.555 0)
			(effects
				(font
					(size 1.27 1.27)
					(thickness 0.15)
				)
				(justify left bottom)
				(hide yes)
			)
		)
		(property "Datasheet" "https://www.bourns.com/docs/product-datasheets/cr.pdf"
			(at 292.735 125.095 0)
			(effects
				(font
					(size 1.27 1.27)
					(thickness 0.15)
				)
				(justify left bottom)
				(hide yes)
			)
		)
		(property "Description" ""
			(at 272.415 107.315 0)
			(effects
				(font
					(size 1.27 1.27)
				)
			)
		)
		(property "Manufacturer" "Bourns"
			(at 292.735 130.175 0)
			(effects
				(font
					(size 1.27 1.27)
					(thickness 0.15)
				)
				(justify left bottom)
				(hide yes)
			)
		)
		(property "MPN" "CR0402-FX-22R0GLF"
			(at 292.735 127.635 0)
			(effects
				(font
					(size 1.27 1.27)
					(thickness 0.15)
				)
				(justify left bottom)
				(hide yes)
			)
		)
		(property "Val" "22R"
			(at 279.4 106.045 0)
			(effects
				(font
					(size 1.27 1.27)
					(thickness 0.15)
				)
			)
		)
		(property "License" "Apache-2.0"
			(at 292.735 132.715 0)
			(effects
				(font
					(size 1.27 1.27)
					(thickness 0.15)
				)
				(justify left bottom)
				(hide yes)
			)
		)
		(property "Author" "Antmicro"
			(at 292.735 135.255 0)
			(effects
				(font
					(size 1.27 1.27)
					(thickness 0.15)
				)
				(justify left bottom)
				(hide yes)
			)
		)
		(property "Tolerance" "1%"
			(at 292.735 117.475 0)
			(effects
				(font
					(size 1.27 1.27)
				)
				(justify left bottom)
				(hide yes)
			)
		)
		(pin "1"
		)
		(pin "2"
		)
		(instances
			(project "sodimm-ddr5-tester"
				(path ""
					(reference "R47")
					(unit 1)
				)
			)
		)
	)
	(symbol
		(lib_id "antmicroResistors0402:R_22R_0402")
		(at 272.415 112.395 0)
		(unit 1)
		(exclude_from_sim no)
		(in_bom yes)
		(on_board yes)
		(dnp no)
		(property "Reference" "R49"
			(at 270.51 111.125 0)
			(effects
				(font
					(size 1.27 1.27)
				)
			)
		)
		(property "Value" "R_22R_0402"
			(at 292.735 125.095 0)
			(effects
				(font
					(size 1.27 1.27)
					(thickness 0.15)
				)
				(justify left bottom)
				(hide yes)
			)
		)
		(property "Footprint" "antmicro-footprints:R_0402_1005Metric"
			(at 292.735 127.635 0)
			(effects
				(font
					(size 1.27 1.27)
					(thickness 0.15)
				)
				(justify left bottom)
				(hide yes)
			)
		)
		(property "Datasheet" "https://www.bourns.com/docs/product-datasheets/cr.pdf"
			(at 292.735 130.175 0)
			(effects
				(font
					(size 1.27 1.27)
					(thickness 0.15)
				)
				(justify left bottom)
				(hide yes)
			)
		)
		(property "Description" ""
			(at 272.415 112.395 0)
			(effects
				(font
					(size 1.27 1.27)
				)
			)
		)
		(property "Manufacturer" "Bourns"
			(at 292.735 135.255 0)
			(effects
				(font
					(size 1.27 1.27)
					(thickness 0.15)
				)
				(justify left bottom)
				(hide yes)
			)
		)
		(property "MPN" "CR0402-FX-22R0GLF"
			(at 292.735 132.715 0)
			(effects
				(font
					(size 1.27 1.27)
					(thickness 0.15)
				)
				(justify left bottom)
				(hide yes)
			)
		)
		(property "Val" "22R"
			(at 279.4 111.125 0)
			(effects
				(font
					(size 1.27 1.27)
					(thickness 0.15)
				)
			)
		)
		(property "License" "Apache-2.0"
			(at 292.735 137.795 0)
			(effects
				(font
					(size 1.27 1.27)
					(thickness 0.15)
				)
				(justify left bottom)
				(hide yes)
			)
		)
		(property "Author" "Antmicro"
			(at 292.735 140.335 0)
			(effects
				(font
					(size 1.27 1.27)
					(thickness 0.15)
				)
				(justify left bottom)
				(hide yes)
			)
		)
		(property "Tolerance" "1%"
			(at 292.735 122.555 0)
			(effects
				(font
					(size 1.27 1.27)
				)
				(justify left bottom)
				(hide yes)
			)
		)
		(pin "1"
		)
		(pin "2"
		)
		(instances
			(project "sodimm-ddr5-tester"
				(path ""
					(reference "R49")
					(unit 1)
				)
			)
		)
	)
	(symbol
		(lib_id "antmicroResistors0402:R_22R_0402")
		(at 272.415 114.935 0)
		(unit 1)
		(exclude_from_sim no)
		(in_bom yes)
		(on_board yes)
		(dnp no)
		(property "Reference" "R50"
			(at 270.51 113.665 0)
			(effects
				(font
					(size 1.27 1.27)
				)
			)
		)
		(property "Value" "R_22R_0402"
			(at 292.735 127.635 0)
			(effects
				(font
					(size 1.27 1.27)
					(thickness 0.15)
				)
				(justify left bottom)
				(hide yes)
			)
		)
		(property "Footprint" "antmicro-footprints:R_0402_1005Metric"
			(at 292.735 130.175 0)
			(effects
				(font
					(size 1.27 1.27)
					(thickness 0.15)
				)
				(justify left bottom)
				(hide yes)
			)
		)
		(property "Datasheet" "https://www.bourns.com/docs/product-datasheets/cr.pdf"
			(at 292.735 132.715 0)
			(effects
				(font
					(size 1.27 1.27)
					(thickness 0.15)
				)
				(justify left bottom)
				(hide yes)
			)
		)
		(property "Description" ""
			(at 272.415 114.935 0)
			(effects
				(font
					(size 1.27 1.27)
				)
			)
		)
		(property "Manufacturer" "Bourns"
			(at 292.735 137.795 0)
			(effects
				(font
					(size 1.27 1.27)
					(thickness 0.15)
				)
				(justify left bottom)
				(hide yes)
			)
		)
		(property "MPN" "CR0402-FX-22R0GLF"
			(at 292.735 135.255 0)
			(effects
				(font
					(size 1.27 1.27)
					(thickness 0.15)
				)
				(justify left bottom)
				(hide yes)
			)
		)
		(property "Val" "22R"
			(at 279.4 113.665 0)
			(effects
				(font
					(size 1.27 1.27)
					(thickness 0.15)
				)
			)
		)
		(property "License" "Apache-2.0"
			(at 292.735 140.335 0)
			(effects
				(font
					(size 1.27 1.27)
					(thickness 0.15)
				)
				(justify left bottom)
				(hide yes)
			)
		)
		(property "Author" "Antmicro"
			(at 292.735 142.875 0)
			(effects
				(font
					(size 1.27 1.27)
					(thickness 0.15)
				)
				(justify left bottom)
				(hide yes)
			)
		)
		(property "Tolerance" "1%"
			(at 292.735 125.095 0)
			(effects
				(font
					(size 1.27 1.27)
				)
				(justify left bottom)
				(hide yes)
			)
		)
		(pin "1"
		)
		(pin "2"
		)
		(instances
			(project "sodimm-ddr5-tester"
				(path ""
					(reference "R50")
					(unit 1)
				)
			)
		)
	)
	(symbol
		(lib_id "antmicroResistors0402:R_22R_0402")
		(at 272.415 109.855 0)
		(unit 1)
		(exclude_from_sim no)
		(in_bom yes)
		(on_board yes)
		(dnp no)
		(property "Reference" "R48"
			(at 270.51 108.585 0)
			(effects
				(font
					(size 1.27 1.27)
				)
			)
		)
		(property "Value" "R_22R_0402"
			(at 292.735 122.555 0)
			(effects
				(font
					(size 1.27 1.27)
					(thickness 0.15)
				)
				(justify left bottom)
				(hide yes)
			)
		)
		(property "Footprint" "antmicro-footprints:R_0402_1005Metric"
			(at 292.735 125.095 0)
			(effects
				(font
					(size 1.27 1.27)
					(thickness 0.15)
				)
				(justify left bottom)
				(hide yes)
			)
		)
		(property "Datasheet" "https://www.bourns.com/docs/product-datasheets/cr.pdf"
			(at 292.735 127.635 0)
			(effects
				(font
					(size 1.27 1.27)
					(thickness 0.15)
				)
				(justify left bottom)
				(hide yes)
			)
		)
		(property "Description" ""
			(at 272.415 109.855 0)
			(effects
				(font
					(size 1.27 1.27)
				)
			)
		)
		(property "Manufacturer" "Bourns"
			(at 292.735 132.715 0)
			(effects
				(font
					(size 1.27 1.27)
					(thickness 0.15)
				)
				(justify left bottom)
				(hide yes)
			)
		)
		(property "MPN" "CR0402-FX-22R0GLF"
			(at 292.735 130.175 0)
			(effects
				(font
					(size 1.27 1.27)
					(thickness 0.15)
				)
				(justify left bottom)
				(hide yes)
			)
		)
		(property "Val" "22R"
			(at 279.4 108.585 0)
			(effects
				(font
					(size 1.27 1.27)
					(thickness 0.15)
				)
			)
		)
		(property "License" "Apache-2.0"
			(at 292.735 135.255 0)
			(effects
				(font
					(size 1.27 1.27)
					(thickness 0.15)
				)
				(justify left bottom)
				(hide yes)
			)
		)
		(property "Author" "Antmicro"
			(at 292.735 137.795 0)
			(effects
				(font
					(size 1.27 1.27)
					(thickness 0.15)
				)
				(justify left bottom)
				(hide yes)
			)
		)
		(property "Tolerance" "1%"
			(at 292.735 120.015 0)
			(effects
				(font
					(size 1.27 1.27)
				)
				(justify left bottom)
				(hide yes)
			)
		)
		(pin "1"
		)
		(pin "2"
		)
		(instances
			(project "sodimm-ddr5-tester"
				(path ""
					(reference "R48")
					(unit 1)
				)
			)
		)
	)
	(symbol
		(lib_id "antmicropower:GND")
		(at 93.345 186.69 0)
		(unit 1)
		(exclude_from_sim no)
		(in_bom yes)
		(on_board yes)
		(dnp no)
		(fields_autoplaced yes)
		(property "Reference" "#PWR0234"
			(at 93.345 193.04 0)
			(effects
				(font
					(size 1.27 1.27)
				)
				(hide yes)
			)
		)
		(property "Value" "GND"
			(at 95.25 187.96 0)
			(effects
				(font
					(size 1.27 1.27)
					(thickness 0.15)
				)
				(justify left)
			)
		)
		(property "Footprint" ""
			(at 102.235 194.31 0)
			(effects
				(font
					(size 1.27 1.27)
					(thickness 0.15)
				)
				(justify left bottom)
				(hide yes)
			)
		)
		(property "Datasheet" ""
			(at 102.235 199.39 0)
			(effects
				(font
					(size 1.27 1.27)
					(thickness 0.15)
				)
				(justify left bottom)
				(hide yes)
			)
		)
		(property "Description" ""
			(at 102.235 201.93 0)
			(effects
				(font
					(size 1.27 1.27)
				)
				(justify left bottom)
				(hide yes)
			)
		)
		(property "Author" "Antmicro"
			(at 102.235 194.31 0)
			(effects
				(font
					(size 1.27 1.27)
					(thickness 0.15)
				)
				(justify left bottom)
				(hide yes)
			)
		)
		(property "License" "Apache-2.0"
			(at 102.235 196.85 0)
			(effects
				(font
					(size 1.27 1.27)
					(thickness 0.15)
				)
				(justify left bottom)
				(hide yes)
			)
		)
		(pin "1"
		)
		(instances
			(project "sodimm-ddr5-tester"
				(path ""
					(reference "#PWR0234")
					(unit 1)
				)
			)
		)
	)
	(symbol
		(lib_id "antmicroTestPoints:TP_1mm_SMD")
		(at 172.72 129.54 0)
		(unit 1)
		(exclude_from_sim no)
		(in_bom yes)
		(on_board yes)
		(dnp no)
		(property "Reference" "TP1"
			(at 179.705 129.54 0)
			(effects
				(font
					(size 1.27 1.27)
				)
			)
		)
		(property "Value" "TP_1mm_SMD"
			(at 187.96 137.16 0)
			(effects
				(font
					(size 1.27 1.27)
					(thickness 0.15)
				)
				(justify left bottom)
				(hide yes)
			)
		)
		(property "Footprint" "antmicro-footprints:TP_SMD_1mm"
			(at 187.96 139.7 0)
			(effects
				(font
					(size 1.27 1.27)
					(thickness 0.15)
				)
				(justify left bottom)
				(hide yes)
			)
		)
		(property "Datasheet" ""
			(at 187.96 142.24 0)
			(effects
				(font
					(size 1.27 1.27)
					(thickness 0.15)
				)
				(justify left bottom)
				(hide yes)
			)
		)
		(property "Description" ""
			(at 172.72 129.54 0)
			(effects
				(font
					(size 1.27 1.27)
				)
			)
		)
		(property "MPN" ""
			(at 172.72 129.54 0)
			(effects
				(font
					(size 1.27 1.27)
				)
				(hide yes)
			)
		)
		(property "Manufacturer" ""
			(at 172.72 129.54 0)
			(effects
				(font
					(size 1.27 1.27)
				)
				(hide yes)
			)
		)
		(property "Author" "Antmicro"
			(at 187.96 144.78 0)
			(effects
				(font
					(size 1.27 1.27)
					(thickness 0.15)
				)
				(justify left bottom)
				(hide yes)
			)
		)
		(property "License" "Apache-2.0"
			(at 187.96 147.32 0)
			(effects
				(font
					(size 1.27 1.27)
					(thickness 0.15)
				)
				(justify left bottom)
				(hide yes)
			)
		)
		(pin "1"
		)
		(instances
			(project "sodimm-ddr5-tester"
				(path ""
					(reference "TP1")
					(unit 1)
				)
			)
		)
	)
	(symbol
		(lib_id "antmicropower:GND")
		(at 136.525 57.15 0)
		(mirror y)
		(unit 1)
		(exclude_from_sim no)
		(in_bom yes)
		(on_board yes)
		(dnp no)
		(property "Reference" "#PWR0212"
			(at 136.525 63.5 0)
			(effects
				(font
					(size 1.27 1.27)
				)
				(hide yes)
			)
		)
		(property "Value" "GND"
			(at 138.43 61.595 0)
			(effects
				(font
					(size 1.27 1.27)
					(thickness 0.15)
				)
				(justify left bottom)
			)
		)
		(property "Footprint" ""
			(at 127.635 64.77 0)
			(effects
				(font
					(size 1.27 1.27)
					(thickness 0.15)
				)
				(justify left bottom)
				(hide yes)
			)
		)
		(property "Datasheet" ""
			(at 127.635 69.85 0)
			(effects
				(font
					(size 1.27 1.27)
					(thickness 0.15)
				)
				(justify left bottom)
				(hide yes)
			)
		)
		(property "Description" ""
			(at 127.635 72.39 0)
			(effects
				(font
					(size 1.27 1.27)
				)
				(justify left bottom)
				(hide yes)
			)
		)
		(property "Author" "Antmicro"
			(at 127.635 64.77 0)
			(effects
				(font
					(size 1.27 1.27)
					(thickness 0.15)
				)
				(justify left bottom)
				(hide yes)
			)
		)
		(property "License" "Apache-2.0"
			(at 127.635 67.31 0)
			(effects
				(font
					(size 1.27 1.27)
					(thickness 0.15)
				)
				(justify left bottom)
				(hide yes)
			)
		)
		(pin "1"
		)
		(instances
			(project "sodimm-ddr5-tester"
				(path ""
					(reference "#PWR0212")
					(unit 1)
				)
			)
		)
	)
	(symbol
		(lib_id "antmicroCapacitors0402:C_100n_0402")
		(at 372.11 173.99 90)
		(unit 1)
		(exclude_from_sim no)
		(in_bom yes)
		(on_board yes)
		(dnp no)
		(fields_autoplaced yes)
		(property "Reference" "C236"
			(at 374.4341 170.613 90)
			(effects
				(font
					(size 1.27 1.27)
					(thickness 0.15)
				)
				(justify right)
			)
		)
		(property "Value" "C_100n_0402"
			(at 382.27 153.67 0)
			(effects
				(font
					(size 1.27 1.27)
					(thickness 0.15)
				)
				(justify left bottom)
				(hide yes)
			)
		)
		(property "Footprint" "antmicro-footprints:C_0402_1005Metric"
			(at 384.81 153.67 0)
			(effects
				(font
					(size 1.27 1.27)
					(thickness 0.15)
				)
				(justify left bottom)
				(hide yes)
			)
		)
		(property "Datasheet" "https://www.murata.com/products/productdetail?partno=GRM155R61H104KE14%23"
			(at 387.35 153.67 0)
			(effects
				(font
					(size 1.27 1.27)
					(thickness 0.15)
				)
				(justify left bottom)
				(hide yes)
			)
		)
		(property "Description" ""
			(at 372.11 173.99 0)
			(effects
				(font
					(size 1.27 1.27)
				)
			)
		)
		(property "MPN" "GRM155R61H104KE14D"
			(at 389.89 153.67 0)
			(effects
				(font
					(size 1.27 1.27)
					(thickness 0.15)
				)
				(justify left bottom)
				(hide yes)
			)
		)
		(property "Manufacturer" "Murata"
			(at 392.43 153.67 0)
			(effects
				(font
					(size 1.27 1.27)
					(thickness 0.15)
				)
				(justify left bottom)
				(hide yes)
			)
		)
		(property "License" "Apache-2.0"
			(at 394.97 153.67 0)
			(effects
				(font
					(size 1.27 1.27)
					(thickness 0.15)
				)
				(justify left bottom)
				(hide yes)
			)
		)
		(property "Author" "Antmicro"
			(at 397.51 153.67 0)
			(effects
				(font
					(size 1.27 1.27)
					(thickness 0.15)
				)
				(justify left bottom)
				(hide yes)
			)
		)
		(property "Val" "100n"
			(at 374.4341 173.1367 90)
			(effects
				(font
					(size 1.27 1.27)
					(thickness 0.15)
				)
				(justify right)
			)
		)
		(property "Voltage" "50V"
			(at 400.05 153.67 0)
			(effects
				(font
					(size 1.27 1.27)
				)
				(justify left bottom)
				(hide yes)
			)
		)
		(property "Dielectric" "X5R"
			(at 402.59 153.67 0)
			(effects
				(font
					(size 1.27 1.27)
				)
				(justify left bottom)
				(hide yes)
			)
		)
		(pin "1"
		)
		(pin "2"
		)
		(instances
			(project "sodimm-ddr5-tester"
				(path ""
					(reference "C236")
					(unit 1)
				)
			)
		)
	)
	(symbol
		(lib_id "antmicroTestPoints:TP_1mm_SMD")
		(at 264.16 275.59 270)
		(unit 1)
		(exclude_from_sim no)
		(in_bom yes)
		(on_board yes)
		(dnp no)
		(property "Reference" "TP49"
			(at 264.16 280.5628 90)
			(effects
				(font
					(size 1.27 1.27)
				)
			)
		)
		(property "Value" "TP_1mm_SMD"
			(at 256.54 290.83 0)
			(effects
				(font
					(size 1.27 1.27)
					(thickness 0.15)
				)
				(justify left bottom)
				(hide yes)
			)
		)
		(property "Footprint" "antmicro-footprints:TP_SMD_1mm"
			(at 254 290.83 0)
			(effects
				(font
					(size 1.27 1.27)
					(thickness 0.15)
				)
				(justify left bottom)
				(hide yes)
			)
		)
		(property "Datasheet" ""
			(at 251.46 290.83 0)
			(effects
				(font
					(size 1.27 1.27)
					(thickness 0.15)
				)
				(justify left bottom)
				(hide yes)
			)
		)
		(property "Description" ""
			(at 264.16 275.59 0)
			(effects
				(font
					(size 1.27 1.27)
				)
			)
		)
		(property "MPN" ""
			(at 264.16 275.59 0)
			(effects
				(font
					(size 1.27 1.27)
				)
				(hide yes)
			)
		)
		(property "Manufacturer" ""
			(at 264.16 275.59 0)
			(effects
				(font
					(size 1.27 1.27)
				)
				(hide yes)
			)
		)
		(property "Author" "Antmicro"
			(at 248.92 290.83 0)
			(effects
				(font
					(size 1.27 1.27)
					(thickness 0.15)
				)
				(justify left bottom)
				(hide yes)
			)
		)
		(property "License" "Apache-2.0"
			(at 246.38 290.83 0)
			(effects
				(font
					(size 1.27 1.27)
					(thickness 0.15)
				)
				(justify left bottom)
				(hide yes)
			)
		)
		(pin "1"
		)
		(instances
			(project "sodimm-ddr5-tester"
				(path ""
					(reference "TP49")
					(unit 1)
				)
			)
		)
	)
	(symbol
		(lib_id "antmicroResistors0402:R_5k11_0402")
		(at 77.47 52.07 0)
		(mirror y)
		(unit 1)
		(exclude_from_sim no)
		(in_bom yes)
		(on_board yes)
		(dnp no)
		(property "Reference" "R68"
			(at 79.375 50.8 0)
			(effects
				(font
					(size 1.27 1.27)
				)
			)
		)
		(property "Value" "R_5k11_0402"
			(at 57.15 64.77 0)
			(effects
				(font
					(size 1.27 1.27)
					(thickness 0.15)
				)
				(justify left bottom)
				(hide yes)
			)
		)
		(property "Footprint" "antmicro-footprints:R_0402_1005Metric"
			(at 57.15 67.31 0)
			(effects
				(font
					(size 1.27 1.27)
					(thickness 0.15)
				)
				(justify left bottom)
				(hide yes)
			)
		)
		(property "Datasheet" "https://www.bourns.com/docs/product-datasheets/cr.pdf"
			(at 57.15 69.85 0)
			(effects
				(font
					(size 1.27 1.27)
					(thickness 0.15)
				)
				(justify left bottom)
				(hide yes)
			)
		)
		(property "Description" ""
			(at 77.47 52.07 0)
			(effects
				(font
					(size 1.27 1.27)
				)
			)
		)
		(property "Manufacturer" "Bourns"
			(at 57.15 74.93 0)
			(effects
				(font
					(size 1.27 1.27)
					(thickness 0.15)
				)
				(justify left bottom)
				(hide yes)
			)
		)
		(property "MPN" "CR0402-FX-5111GLF"
			(at 57.15 72.39 0)
			(effects
				(font
					(size 1.27 1.27)
					(thickness 0.15)
				)
				(justify left bottom)
				(hide yes)
			)
		)
		(property "Val" "5k11"
			(at 70.485 50.8 0)
			(effects
				(font
					(size 1.27 1.27)
					(thickness 0.15)
				)
			)
		)
		(property "License" "Apache-2.0"
			(at 57.15 77.47 0)
			(effects
				(font
					(size 1.27 1.27)
					(thickness 0.15)
				)
				(justify left bottom)
				(hide yes)
			)
		)
		(property "Author" "Antmicro"
			(at 57.15 80.01 0)
			(effects
				(font
					(size 1.27 1.27)
					(thickness 0.15)
				)
				(justify left bottom)
				(hide yes)
			)
		)
		(property "Tolerance" "1%"
			(at 57.15 62.23 0)
			(effects
				(font
					(size 1.27 1.27)
				)
				(justify left bottom)
				(hide yes)
			)
		)
		(pin "1"
		)
		(pin "2"
		)
		(instances
			(project "sodimm-ddr5-tester"
				(path ""
					(reference "R68")
					(unit 1)
				)
			)
		)
	)
	(symbol
		(lib_id "antmicropower:GND")
		(at 372.237 111.76 0)
		(unit 1)
		(exclude_from_sim no)
		(in_bom yes)
		(on_board yes)
		(dnp no)
		(property "Reference" "#PWR0197"
			(at 372.237 118.11 0)
			(effects
				(font
					(size 1.27 1.27)
				)
				(hide yes)
			)
		)
		(property "Value" "GND"
			(at 370.332 116.205 0)
			(effects
				(font
					(size 1.27 1.27)
					(thickness 0.15)
				)
				(justify left bottom)
			)
		)
		(property "Footprint" ""
			(at 381.127 119.38 0)
			(effects
				(font
					(size 1.27 1.27)
					(thickness 0.15)
				)
				(justify left bottom)
				(hide yes)
			)
		)
		(property "Datasheet" ""
			(at 381.127 124.46 0)
			(effects
				(font
					(size 1.27 1.27)
					(thickness 0.15)
				)
				(justify left bottom)
				(hide yes)
			)
		)
		(property "Description" ""
			(at 381.127 127 0)
			(effects
				(font
					(size 1.27 1.27)
				)
				(justify left bottom)
				(hide yes)
			)
		)
		(property "Author" "Antmicro"
			(at 381.127 119.38 0)
			(effects
				(font
					(size 1.27 1.27)
					(thickness 0.15)
				)
				(justify left bottom)
				(hide yes)
			)
		)
		(property "License" "Apache-2.0"
			(at 381.127 121.92 0)
			(effects
				(font
					(size 1.27 1.27)
					(thickness 0.15)
				)
				(justify left bottom)
				(hide yes)
			)
		)
		(pin "1"
		)
		(instances
			(project "sodimm-ddr5-tester"
				(path ""
					(reference "#PWR0197")
					(unit 1)
				)
			)
		)
	)
	(symbol
		(lib_id "antmicroResistors0402:R_22R_0402")
		(at 179.705 140.97 0)
		(unit 1)
		(exclude_from_sim no)
		(in_bom no)
		(on_board yes)
		(dnp yes)
		(property "Reference" "R57"
			(at 186.69 139.7 0)
			(effects
				(font
					(size 1.27 1.27)
				)
			)
		)
		(property "Value" "R_22R_0402"
			(at 200.025 153.67 0)
			(effects
				(font
					(size 1.27 1.27)
					(thickness 0.15)
				)
				(justify left bottom)
				(hide yes)
			)
		)
		(property "Footprint" "antmicro-footprints:R_0402_1005Metric"
			(at 200.025 156.21 0)
			(effects
				(font
					(size 1.27 1.27)
					(thickness 0.15)
				)
				(justify left bottom)
				(hide yes)
			)
		)
		(property "Datasheet" "https://www.bourns.com/docs/product-datasheets/cr.pdf"
			(at 200.025 158.75 0)
			(effects
				(font
					(size 1.27 1.27)
					(thickness 0.15)
				)
				(justify left bottom)
				(hide yes)
			)
		)
		(property "Description" ""
			(at 179.705 140.97 0)
			(effects
				(font
					(size 1.27 1.27)
				)
			)
		)
		(property "Manufacturer" "Bourns"
			(at 200.025 163.83 0)
			(effects
				(font
					(size 1.27 1.27)
					(thickness 0.15)
				)
				(justify left bottom)
				(hide yes)
			)
		)
		(property "MPN" "CR0402-FX-22R0GLF"
			(at 200.025 161.29 0)
			(effects
				(font
					(size 1.27 1.27)
					(thickness 0.15)
				)
				(justify left bottom)
				(hide yes)
			)
		)
		(property "Val" "22R"
			(at 177.8 139.7 0)
			(effects
				(font
					(size 1.27 1.27)
					(thickness 0.15)
				)
			)
		)
		(property "License" "Apache-2.0"
			(at 200.025 166.37 0)
			(effects
				(font
					(size 1.27 1.27)
					(thickness 0.15)
				)
				(justify left bottom)
				(hide yes)
			)
		)
		(property "Author" "Antmicro"
			(at 200.025 168.91 0)
			(effects
				(font
					(size 1.27 1.27)
					(thickness 0.15)
				)
				(justify left bottom)
				(hide yes)
			)
		)
		(property "Tolerance" "1%"
			(at 200.025 151.13 0)
			(effects
				(font
					(size 1.27 1.27)
				)
				(justify left bottom)
				(hide yes)
			)
		)
		(pin "1"
		)
		(pin "2"
		)
		(instances
			(project "sodimm-ddr5-tester"
				(path ""
					(reference "R57")
					(unit 1)
				)
			)
		)
	)
	(symbol
		(lib_id "antmicropower:+3V3")
		(at 372.11 186.055 0)
		(unit 1)
		(exclude_from_sim no)
		(in_bom yes)
		(on_board yes)
		(dnp no)
		(property "Reference" "#PWR016"
			(at 372.11 189.865 0)
			(effects
				(font
					(size 1.27 1.27)
				)
				(hide yes)
			)
		)
		(property "Value" "+3V3"
			(at 368.935 183.515 0)
			(effects
				(font
					(size 1.27 1.27)
					(thickness 0.15)
				)
				(justify left bottom)
			)
		)
		(property "Footprint" ""
			(at 387.35 193.675 0)
			(effects
				(font
					(size 1.27 1.27)
					(thickness 0.15)
				)
				(justify left bottom)
				(hide yes)
			)
		)
		(property "Datasheet" ""
			(at 387.35 196.215 0)
			(effects
				(font
					(size 1.27 1.27)
					(thickness 0.15)
				)
				(justify left bottom)
				(hide yes)
			)
		)
		(property "Description" ""
			(at 372.11 186.055 0)
			(effects
				(font
					(size 1.27 1.27)
				)
			)
		)
		(property "Author" "Antmicro"
			(at 387.35 188.595 0)
			(effects
				(font
					(size 1.27 1.27)
					(thickness 0.15)
				)
				(justify left bottom)
				(hide yes)
			)
		)
		(property "License" "Apache-2.0"
			(at 387.35 191.135 0)
			(effects
				(font
					(size 1.27 1.27)
					(thickness 0.15)
				)
				(justify left bottom)
				(hide yes)
			)
		)
		(pin "1"
		)
		(instances
			(project "sodimm-ddr5-tester"
				(path ""
					(reference "#PWR016")
					(unit 1)
				)
			)
		)
	)
	(symbol
		(lib_id "antmicropower:GND")
		(at 251.46 276.86 0)
		(mirror y)
		(unit 1)
		(exclude_from_sim no)
		(in_bom yes)
		(on_board yes)
		(dnp no)
		(property "Reference" "#PWR050"
			(at 251.46 283.21 0)
			(effects
				(font
					(size 1.27 1.27)
				)
				(hide yes)
			)
		)
		(property "Value" "GND"
			(at 249.428 280.67 0)
			(effects
				(font
					(size 1.27 1.27)
					(thickness 0.15)
				)
				(justify right)
			)
		)
		(property "Footprint" ""
			(at 242.57 284.48 0)
			(effects
				(font
					(size 1.27 1.27)
					(thickness 0.15)
				)
				(justify left bottom)
				(hide yes)
			)
		)
		(property "Datasheet" ""
			(at 242.57 289.56 0)
			(effects
				(font
					(size 1.27 1.27)
					(thickness 0.15)
				)
				(justify left bottom)
				(hide yes)
			)
		)
		(property "Description" ""
			(at 242.57 292.1 0)
			(effects
				(font
					(size 1.27 1.27)
				)
				(justify left bottom)
				(hide yes)
			)
		)
		(property "Author" "Antmicro"
			(at 242.57 284.48 0)
			(effects
				(font
					(size 1.27 1.27)
					(thickness 0.15)
				)
				(justify left bottom)
				(hide yes)
			)
		)
		(property "License" "Apache-2.0"
			(at 242.57 287.02 0)
			(effects
				(font
					(size 1.27 1.27)
					(thickness 0.15)
				)
				(justify left bottom)
				(hide yes)
			)
		)
		(pin "1"
		)
		(instances
			(project "sodimm-ddr5-tester"
				(path ""
					(reference "#PWR050")
					(unit 1)
				)
			)
		)
	)
	(symbol
		(lib_id "antmicropower:GND")
		(at 264.16 201.93 0)
		(mirror y)
		(unit 1)
		(exclude_from_sim no)
		(in_bom yes)
		(on_board yes)
		(dnp no)
		(property "Reference" "#PWR09"
			(at 264.16 208.28 0)
			(effects
				(font
					(size 1.27 1.27)
				)
				(hide yes)
			)
		)
		(property "Value" "GND"
			(at 266.065 206.375 0)
			(effects
				(font
					(size 1.27 1.27)
					(thickness 0.15)
				)
				(justify left bottom)
			)
		)
		(property "Footprint" ""
			(at 255.27 209.55 0)
			(effects
				(font
					(size 1.27 1.27)
					(thickness 0.15)
				)
				(justify left bottom)
				(hide yes)
			)
		)
		(property "Datasheet" ""
			(at 255.27 214.63 0)
			(effects
				(font
					(size 1.27 1.27)
					(thickness 0.15)
				)
				(justify left bottom)
				(hide yes)
			)
		)
		(property "Description" ""
			(at 255.27 217.17 0)
			(effects
				(font
					(size 1.27 1.27)
				)
				(justify left bottom)
				(hide yes)
			)
		)
		(property "Author" "Antmicro"
			(at 255.27 209.55 0)
			(effects
				(font
					(size 1.27 1.27)
					(thickness 0.15)
				)
				(justify left bottom)
				(hide yes)
			)
		)
		(property "License" "Apache-2.0"
			(at 255.27 212.09 0)
			(effects
				(font
					(size 1.27 1.27)
					(thickness 0.15)
				)
				(justify left bottom)
				(hide yes)
			)
		)
		(pin "1"
		)
		(instances
			(project "sodimm-ddr5-tester"
				(path ""
					(reference "#PWR09")
					(unit 1)
				)
			)
		)
	)
	(symbol
		(lib_id "antmicroResistors0402:R_0R_0402")
		(at 281.305 135.89 180)
		(unit 1)
		(exclude_from_sim no)
		(in_bom no)
		(on_board yes)
		(dnp yes)
		(property "Reference" "R91"
			(at 283.845 134.62 0)
			(effects
				(font
					(size 1.27 1.27)
				)
			)
		)
		(property "Value" "R_0R_0402"
			(at 260.985 123.19 0)
			(effects
				(font
					(size 1.27 1.27)
					(thickness 0.15)
				)
				(justify left bottom)
				(hide yes)
			)
		)
		(property "Footprint" "antmicro-footprints:R_0402_1005Metric"
			(at 260.985 120.65 0)
			(effects
				(font
					(size 1.27 1.27)
					(thickness 0.15)
				)
				(justify left bottom)
				(hide yes)
			)
		)
		(property "Datasheet" "https://industrial.panasonic.com/cdbs/www-data/pdf/RDA0000/AOA0000C301.pdf"
			(at 260.985 118.11 0)
			(effects
				(font
					(size 1.27 1.27)
					(thickness 0.15)
				)
				(justify left bottom)
				(hide yes)
			)
		)
		(property "Description" ""
			(at 281.305 135.89 0)
			(effects
				(font
					(size 1.27 1.27)
				)
			)
		)
		(property "Manufacturer" "Panasonic"
			(at 260.985 113.03 0)
			(effects
				(font
					(size 1.27 1.27)
					(thickness 0.15)
				)
				(justify left bottom)
				(hide yes)
			)
		)
		(property "MPN" "ERJ2GE0R00X"
			(at 260.985 115.57 0)
			(effects
				(font
					(size 1.27 1.27)
					(thickness 0.15)
				)
				(justify left bottom)
				(hide yes)
			)
		)
		(property "Val" "0R"
			(at 274.955 134.62 0)
			(effects
				(font
					(size 1.27 1.27)
					(thickness 0.15)
				)
			)
		)
		(property "License" "Apache-2.0"
			(at 260.985 110.49 0)
			(effects
				(font
					(size 1.27 1.27)
					(thickness 0.15)
				)
				(justify left bottom)
				(hide yes)
			)
		)
		(property "Author" "Antmicro"
			(at 260.985 107.95 0)
			(effects
				(font
					(size 1.27 1.27)
					(thickness 0.15)
				)
				(justify left bottom)
				(hide yes)
			)
		)
		(property "Tolerance" "~"
			(at 260.985 125.73 0)
			(effects
				(font
					(size 1.27 1.27)
				)
				(justify left bottom)
				(hide yes)
			)
		)
		(property "Current" "1A"
			(at 278.765 147.955 0)
			(effects
				(font
					(size 1.27 1.27)
					(thickness 0.15)
				)
				(hide yes)
			)
		)
		(pin "1"
		)
		(pin "2"
		)
		(instances
			(project "sodimm-ddr5-tester"
				(path ""
					(reference "R91")
					(unit 1)
				)
			)
		)
	)
	(symbol
		(lib_id "antmicropower:GND")
		(at 101.6 57.15 0)
		(mirror y)
		(unit 1)
		(exclude_from_sim no)
		(in_bom yes)
		(on_board yes)
		(dnp no)
		(fields_autoplaced yes)
		(property "Reference" "#PWR0207"
			(at 101.6 63.5 0)
			(effects
				(font
					(size 1.27 1.27)
				)
				(hide yes)
			)
		)
		(property "Value" "GND"
			(at 104.14 58.42 0)
			(effects
				(font
					(size 1.27 1.27)
					(thickness 0.15)
				)
				(justify right)
			)
		)
		(property "Footprint" ""
			(at 92.71 64.77 0)
			(effects
				(font
					(size 1.27 1.27)
					(thickness 0.15)
				)
				(justify left bottom)
				(hide yes)
			)
		)
		(property "Datasheet" ""
			(at 92.71 69.85 0)
			(effects
				(font
					(size 1.27 1.27)
					(thickness 0.15)
				)
				(justify left bottom)
				(hide yes)
			)
		)
		(property "Description" ""
			(at 92.71 72.39 0)
			(effects
				(font
					(size 1.27 1.27)
				)
				(justify left bottom)
				(hide yes)
			)
		)
		(property "Author" "Antmicro"
			(at 92.71 64.77 0)
			(effects
				(font
					(size 1.27 1.27)
					(thickness 0.15)
				)
				(justify left bottom)
				(hide yes)
			)
		)
		(property "License" "Apache-2.0"
			(at 92.71 67.31 0)
			(effects
				(font
					(size 1.27 1.27)
					(thickness 0.15)
				)
				(justify left bottom)
				(hide yes)
			)
		)
		(pin "1"
		)
		(instances
			(project "sodimm-ddr5-tester"
				(path ""
					(reference "#PWR0207")
					(unit 1)
				)
			)
		)
	)
	(symbol
		(lib_id "antmicroResistors0402:R_0R_0402")
		(at 290.83 138.43 0)
		(unit 1)
		(exclude_from_sim no)
		(in_bom yes)
		(on_board yes)
		(dnp no)
		(property "Reference" "R92"
			(at 298.45 137.16 0)
			(effects
				(font
					(size 1.27 1.27)
				)
			)
		)
		(property "Value" "R_0R_0402"
			(at 311.15 151.13 0)
			(effects
				(font
					(size 1.27 1.27)
					(thickness 0.15)
				)
				(justify left bottom)
				(hide yes)
			)
		)
		(property "Footprint" "antmicro-footprints:R_0402_1005Metric"
			(at 311.15 153.67 0)
			(effects
				(font
					(size 1.27 1.27)
					(thickness 0.15)
				)
				(justify left bottom)
				(hide yes)
			)
		)
		(property "Datasheet" "https://industrial.panasonic.com/cdbs/www-data/pdf/RDA0000/AOA0000C301.pdf"
			(at 311.15 156.21 0)
			(effects
				(font
					(size 1.27 1.27)
					(thickness 0.15)
				)
				(justify left bottom)
				(hide yes)
			)
		)
		(property "Description" ""
			(at 290.83 138.43 0)
			(effects
				(font
					(size 1.27 1.27)
				)
			)
		)
		(property "Manufacturer" "Panasonic"
			(at 311.15 161.29 0)
			(effects
				(font
					(size 1.27 1.27)
					(thickness 0.15)
				)
				(justify left bottom)
				(hide yes)
			)
		)
		(property "MPN" "ERJ2GE0R00X"
			(at 311.15 158.75 0)
			(effects
				(font
					(size 1.27 1.27)
					(thickness 0.15)
				)
				(justify left bottom)
				(hide yes)
			)
		)
		(property "Val" "0R"
			(at 289.56 137.16 0)
			(effects
				(font
					(size 1.27 1.27)
					(thickness 0.15)
				)
			)
		)
		(property "License" "Apache-2.0"
			(at 311.15 163.83 0)
			(effects
				(font
					(size 1.27 1.27)
					(thickness 0.15)
				)
				(justify left bottom)
				(hide yes)
			)
		)
		(property "Author" "Antmicro"
			(at 311.15 166.37 0)
			(effects
				(font
					(size 1.27 1.27)
					(thickness 0.15)
				)
				(justify left bottom)
				(hide yes)
			)
		)
		(property "Tolerance" "~"
			(at 311.15 148.59 0)
			(effects
				(font
					(size 1.27 1.27)
				)
				(justify left bottom)
				(hide yes)
			)
		)
		(property "Current" "1A"
			(at 293.37 147.32 0)
			(effects
				(font
					(size 1.27 1.27)
					(thickness 0.15)
				)
				(hide yes)
			)
		)
		(pin "1"
		)
		(pin "2"
		)
		(instances
			(project "sodimm-ddr5-tester"
				(path ""
					(reference "R92")
					(unit 1)
				)
			)
		)
	)
	(symbol
		(lib_id "antmicroTestPoints:TP_1mm_SMD")
		(at 270.51 275.59 270)
		(unit 1)
		(exclude_from_sim no)
		(in_bom yes)
		(on_board yes)
		(dnp no)
		(property "Reference" "TP50"
			(at 270.51 280.5628 90)
			(effects
				(font
					(size 1.27 1.27)
				)
			)
		)
		(property "Value" "TP_1mm_SMD"
			(at 262.89 290.83 0)
			(effects
				(font
					(size 1.27 1.27)
					(thickness 0.15)
				)
				(justify left bottom)
				(hide yes)
			)
		)
		(property "Footprint" "antmicro-footprints:TP_SMD_1mm"
			(at 260.35 290.83 0)
			(effects
				(font
					(size 1.27 1.27)
					(thickness 0.15)
				)
				(justify left bottom)
				(hide yes)
			)
		)
		(property "Datasheet" ""
			(at 257.81 290.83 0)
			(effects
				(font
					(size 1.27 1.27)
					(thickness 0.15)
				)
				(justify left bottom)
				(hide yes)
			)
		)
		(property "Description" ""
			(at 270.51 275.59 0)
			(effects
				(font
					(size 1.27 1.27)
				)
			)
		)
		(property "MPN" ""
			(at 270.51 275.59 0)
			(effects
				(font
					(size 1.27 1.27)
				)
				(hide yes)
			)
		)
		(property "Manufacturer" ""
			(at 270.51 275.59 0)
			(effects
				(font
					(size 1.27 1.27)
				)
				(hide yes)
			)
		)
		(property "Author" "Antmicro"
			(at 255.27 290.83 0)
			(effects
				(font
					(size 1.27 1.27)
					(thickness 0.15)
				)
				(justify left bottom)
				(hide yes)
			)
		)
		(property "License" "Apache-2.0"
			(at 252.73 290.83 0)
			(effects
				(font
					(size 1.27 1.27)
					(thickness 0.15)
				)
				(justify left bottom)
				(hide yes)
			)
		)
		(pin "1"
		)
		(instances
			(project "sodimm-ddr5-tester"
				(path ""
					(reference "TP50")
					(unit 1)
				)
			)
		)
	)
	(symbol
		(lib_id "antmicroTestPoints:TP_1mm_SMD")
		(at 245.11 275.59 270)
		(unit 1)
		(exclude_from_sim no)
		(in_bom yes)
		(on_board yes)
		(dnp no)
		(property "Reference" "TP46"
			(at 245.11 280.5628 90)
			(effects
				(font
					(size 1.27 1.27)
				)
			)
		)
		(property "Value" "TP_1mm_SMD"
			(at 237.49 290.83 0)
			(effects
				(font
					(size 1.27 1.27)
					(thickness 0.15)
				)
				(justify left bottom)
				(hide yes)
			)
		)
		(property "Footprint" "antmicro-footprints:TP_SMD_1mm"
			(at 234.95 290.83 0)
			(effects
				(font
					(size 1.27 1.27)
					(thickness 0.15)
				)
				(justify left bottom)
				(hide yes)
			)
		)
		(property "Datasheet" ""
			(at 232.41 290.83 0)
			(effects
				(font
					(size 1.27 1.27)
					(thickness 0.15)
				)
				(justify left bottom)
				(hide yes)
			)
		)
		(property "Description" ""
			(at 245.11 275.59 0)
			(effects
				(font
					(size 1.27 1.27)
				)
			)
		)
		(property "MPN" ""
			(at 245.11 275.59 0)
			(effects
				(font
					(size 1.27 1.27)
				)
				(hide yes)
			)
		)
		(property "Manufacturer" ""
			(at 245.11 275.59 0)
			(effects
				(font
					(size 1.27 1.27)
				)
				(hide yes)
			)
		)
		(property "Author" "Antmicro"
			(at 229.87 290.83 0)
			(effects
				(font
					(size 1.27 1.27)
					(thickness 0.15)
				)
				(justify left bottom)
				(hide yes)
			)
		)
		(property "License" "Apache-2.0"
			(at 227.33 290.83 0)
			(effects
				(font
					(size 1.27 1.27)
					(thickness 0.15)
				)
				(justify left bottom)
				(hide yes)
			)
		)
		(pin "1"
		)
		(instances
			(project "sodimm-ddr5-tester"
				(path ""
					(reference "TP46")
					(unit 1)
				)
			)
		)
	)
	(symbol
		(lib_id "antmicroCapacitors0603:C_10u_25V_0603")
		(at 101.6 54.61 90)
		(unit 1)
		(exclude_from_sim no)
		(in_bom yes)
		(on_board yes)
		(dnp no)
		(property "Reference" "C109"
			(at 102.235 50.165 90)
			(effects
				(font
					(size 1.27 1.27)
				)
				(justify right)
			)
		)
		(property "Value" "C_10u_25V_0603"
			(at 111.76 34.29 0)
			(effects
				(font
					(size 1.27 1.27)
					(thickness 0.15)
				)
				(justify left bottom)
				(hide yes)
			)
		)
		(property "Footprint" "antmicro-footprints:C_0603_1608Metric"
			(at 114.3 34.29 0)
			(effects
				(font
					(size 1.27 1.27)
					(thickness 0.15)
				)
				(justify left bottom)
				(hide yes)
			)
		)
		(property "Datasheet" "https://product.tdk.com/en/search/capacitor/ceramic/mlcc/info?part_no=C1608X5R1E106M080AC"
			(at 116.84 34.29 0)
			(effects
				(font
					(size 1.27 1.27)
					(thickness 0.15)
				)
				(justify left bottom)
				(hide yes)
			)
		)
		(property "Description" ""
			(at 101.6 54.61 0)
			(effects
				(font
					(size 1.27 1.27)
				)
			)
		)
		(property "Manufacturer" "TDK"
			(at 121.92 34.29 0)
			(effects
				(font
					(size 1.27 1.27)
					(thickness 0.15)
				)
				(justify left bottom)
				(hide yes)
			)
		)
		(property "MPN" "C1608X5R1E106M080AC"
			(at 119.38 34.29 0)
			(effects
				(font
					(size 1.27 1.27)
					(thickness 0.15)
				)
				(justify left bottom)
				(hide yes)
			)
		)
		(property "Val" "10u/25V"
			(at 102.235 53.975 90)
			(effects
				(font
					(size 1.27 1.27)
					(thickness 0.15)
				)
				(justify right)
			)
		)
		(property "License" "Apache-2.0"
			(at 124.46 34.29 0)
			(effects
				(font
					(size 1.27 1.27)
					(thickness 0.15)
				)
				(justify left bottom)
				(hide yes)
			)
		)
		(property "Author" "Antmicro"
			(at 127 34.29 0)
			(effects
				(font
					(size 1.27 1.27)
					(thickness 0.15)
				)
				(justify left bottom)
				(hide yes)
			)
		)
		(property "Voltage" ""
			(at 129.54 34.29 0)
			(effects
				(font
					(size 1.27 1.27)
				)
				(justify left bottom)
				(hide yes)
			)
		)
		(property "Dielectric" ""
			(at 132.08 34.29 0)
			(effects
				(font
					(size 1.27 1.27)
				)
				(justify left bottom)
				(hide yes)
			)
		)
		(pin "1"
		)
		(pin "2"
		)
		(instances
			(project "sodimm-ddr5-tester"
				(path ""
					(reference "C109")
					(unit 1)
				)
			)
		)
	)
	(symbol
		(lib_id "antmicroTestPoints:TP_1mm_SMD")
		(at 251.46 273.05 90)
		(unit 1)
		(exclude_from_sim no)
		(in_bom yes)
		(on_board yes)
		(dnp no)
		(property "Reference" "TP47"
			(at 251.46 268.0772 90)
			(effects
				(font
					(size 1.27 1.27)
				)
			)
		)
		(property "Value" "TP_1mm_SMD"
			(at 259.08 257.81 0)
			(effects
				(font
					(size 1.27 1.27)
					(thickness 0.15)
				)
				(justify left bottom)
				(hide yes)
			)
		)
		(property "Footprint" "antmicro-footprints:TP_SMD_1mm"
			(at 261.62 257.81 0)
			(effects
				(font
					(size 1.27 1.27)
					(thickness 0.15)
				)
				(justify left bottom)
				(hide yes)
			)
		)
		(property "Datasheet" ""
			(at 264.16 257.81 0)
			(effects
				(font
					(size 1.27 1.27)
					(thickness 0.15)
				)
				(justify left bottom)
				(hide yes)
			)
		)
		(property "Description" ""
			(at 251.46 273.05 0)
			(effects
				(font
					(size 1.27 1.27)
				)
			)
		)
		(property "MPN" ""
			(at 251.46 273.05 0)
			(effects
				(font
					(size 1.27 1.27)
				)
				(hide yes)
			)
		)
		(property "Manufacturer" ""
			(at 251.46 273.05 0)
			(effects
				(font
					(size 1.27 1.27)
				)
				(hide yes)
			)
		)
		(property "Author" "Antmicro"
			(at 266.7 257.81 0)
			(effects
				(font
					(size 1.27 1.27)
					(thickness 0.15)
				)
				(justify left bottom)
				(hide yes)
			)
		)
		(property "License" "Apache-2.0"
			(at 269.24 257.81 0)
			(effects
				(font
					(size 1.27 1.27)
					(thickness 0.15)
				)
				(justify left bottom)
				(hide yes)
			)
		)
		(pin "1"
		)
		(instances
			(project "sodimm-ddr5-tester"
				(path ""
					(reference "TP47")
					(unit 1)
				)
			)
		)
	)
	(symbol
		(lib_id "antmicroLogicTranslatorsLevelShifters:TXU0304BQAR")
		(at 245.11 102.235 0)
		(unit 1)
		(exclude_from_sim no)
		(in_bom yes)
		(on_board yes)
		(dnp no)
		(property "Reference" "U7"
			(at 254 95.885 0)
			(effects
				(font
					(size 1.27 1.27)
				)
			)
		)
		(property "Value" "TXU0304BQAR"
			(at 254 98.425 0)
			(effects
				(font
					(size 1.27 1.27)
					(thickness 0.15)
				)
			)
		)
		(property "Footprint" "antmicro-footprints:DHVQFN-14-1EP_2.5x3mm"
			(at 276.86 107.315 0)
			(effects
				(font
					(size 1.27 1.27)
					(thickness 0.15)
				)
				(justify left bottom)
				(hide yes)
			)
		)
		(property "Datasheet" "https://www.ti.com/lit/ds/symlink/txu0304.pdf?ts=1637748643258&ref_url=https%253A%252F%252Fwww.ti.com%252Fproduct%252FTXU0304"
			(at 276.86 109.855 0)
			(effects
				(font
					(size 1.27 1.27)
					(thickness 0.15)
				)
				(justify left bottom)
				(hide yes)
			)
		)
		(property "Description" ""
			(at 245.11 102.235 0)
			(effects
				(font
					(size 1.27 1.27)
				)
			)
		)
		(property "MPN" "TXU0304BQAR"
			(at 276.86 112.395 0)
			(effects
				(font
					(size 1.27 1.27)
					(thickness 0.15)
				)
				(justify left bottom)
				(hide yes)
			)
		)
		(property "Manufacturer" "Texas Instruments"
			(at 276.86 114.935 0)
			(effects
				(font
					(size 1.27 1.27)
					(thickness 0.15)
				)
				(justify left bottom)
				(hide yes)
			)
		)
		(property "Author" "Antmicro"
			(at 276.86 117.475 0)
			(effects
				(font
					(size 1.27 1.27)
					(thickness 0.15)
				)
				(justify left bottom)
				(hide yes)
			)
		)
		(property "License" "Apache-2.0"
			(at 276.86 120.015 0)
			(effects
				(font
					(size 1.27 1.27)
					(thickness 0.15)
				)
				(justify left bottom)
				(hide yes)
			)
		)
		(pin "1"
		)
		(pin "10"
		)
		(pin "11"
		)
		(pin "12"
		)
		(pin "13"
		)
		(pin "14"
		)
		(pin "15"
		)
		(pin "2"
		)
		(pin "3"
		)
		(pin "4"
		)
		(pin "5"
		)
		(pin "6"
		)
		(pin "7"
		)
		(pin "8"
		)
		(pin "9"
		)
		(instances
			(project "sodimm-ddr5-tester"
				(path ""
					(reference "U7")
					(unit 1)
				)
			)
		)
	)
	(symbol
		(lib_id "antmicropower:GND")
		(at 281.94 276.86 0)
		(mirror y)
		(unit 1)
		(exclude_from_sim no)
		(in_bom yes)
		(on_board yes)
		(dnp no)
		(property "Reference" "#PWR0175"
			(at 281.94 283.21 0)
			(effects
				(font
					(size 1.27 1.27)
				)
				(hide yes)
			)
		)
		(property "Value" "GND"
			(at 279.908 280.67 0)
			(effects
				(font
					(size 1.27 1.27)
					(thickness 0.15)
				)
				(justify right)
			)
		)
		(property "Footprint" ""
			(at 273.05 284.48 0)
			(effects
				(font
					(size 1.27 1.27)
					(thickness 0.15)
				)
				(justify left bottom)
				(hide yes)
			)
		)
		(property "Datasheet" ""
			(at 273.05 289.56 0)
			(effects
				(font
					(size 1.27 1.27)
					(thickness 0.15)
				)
				(justify left bottom)
				(hide yes)
			)
		)
		(property "Description" ""
			(at 273.05 292.1 0)
			(effects
				(font
					(size 1.27 1.27)
				)
				(justify left bottom)
				(hide yes)
			)
		)
		(property "Author" "Antmicro"
			(at 273.05 284.48 0)
			(effects
				(font
					(size 1.27 1.27)
					(thickness 0.15)
				)
				(justify left bottom)
				(hide yes)
			)
		)
		(property "License" "Apache-2.0"
			(at 273.05 287.02 0)
			(effects
				(font
					(size 1.27 1.27)
					(thickness 0.15)
				)
				(justify left bottom)
				(hide yes)
			)
		)
		(pin "1"
		)
		(instances
			(project "sodimm-ddr5-tester"
				(path ""
					(reference "#PWR0175")
					(unit 1)
				)
			)
		)
	)
	(symbol
		(lib_id "antmicropower:GND")
		(at 372.11 175.26 0)
		(unit 1)
		(exclude_from_sim no)
		(in_bom yes)
		(on_board yes)
		(dnp no)
		(property "Reference" "#PWR015"
			(at 372.11 181.61 0)
			(effects
				(font
					(size 1.27 1.27)
				)
				(hide yes)
			)
		)
		(property "Value" "GND"
			(at 370.205 179.705 0)
			(effects
				(font
					(size 1.27 1.27)
					(thickness 0.15)
				)
				(justify left bottom)
			)
		)
		(property "Footprint" ""
			(at 381 182.88 0)
			(effects
				(font
					(size 1.27 1.27)
					(thickness 0.15)
				)
				(justify left bottom)
				(hide yes)
			)
		)
		(property "Datasheet" ""
			(at 381 187.96 0)
			(effects
				(font
					(size 1.27 1.27)
					(thickness 0.15)
				)
				(justify left bottom)
				(hide yes)
			)
		)
		(property "Description" ""
			(at 381 190.5 0)
			(effects
				(font
					(size 1.27 1.27)
				)
				(justify left bottom)
				(hide yes)
			)
		)
		(property "Author" "Antmicro"
			(at 381 182.88 0)
			(effects
				(font
					(size 1.27 1.27)
					(thickness 0.15)
				)
				(justify left bottom)
				(hide yes)
			)
		)
		(property "License" "Apache-2.0"
			(at 381 185.42 0)
			(effects
				(font
					(size 1.27 1.27)
					(thickness 0.15)
				)
				(justify left bottom)
				(hide yes)
			)
		)
		(pin "1"
		)
		(instances
			(project "sodimm-ddr5-tester"
				(path ""
					(reference "#PWR015")
					(unit 1)
				)
			)
		)
	)
	(symbol
		(lib_id "antmicroResistors0402:R_0R_0402")
		(at 276.225 133.35 0)
		(unit 1)
		(exclude_from_sim no)
		(in_bom yes)
		(on_board yes)
		(dnp no)
		(property "Reference" "R88"
			(at 283.845 132.08 0)
			(effects
				(font
					(size 1.27 1.27)
				)
			)
		)
		(property "Value" "R_0R_0402"
			(at 296.545 146.05 0)
			(effects
				(font
					(size 1.27 1.27)
					(thickness 0.15)
				)
				(justify left bottom)
				(hide yes)
			)
		)
		(property "Footprint" "antmicro-footprints:R_0402_1005Metric"
			(at 296.545 148.59 0)
			(effects
				(font
					(size 1.27 1.27)
					(thickness 0.15)
				)
				(justify left bottom)
				(hide yes)
			)
		)
		(property "Datasheet" "https://industrial.panasonic.com/cdbs/www-data/pdf/RDA0000/AOA0000C301.pdf"
			(at 296.545 151.13 0)
			(effects
				(font
					(size 1.27 1.27)
					(thickness 0.15)
				)
				(justify left bottom)
				(hide yes)
			)
		)
		(property "Description" ""
			(at 276.225 133.35 0)
			(effects
				(font
					(size 1.27 1.27)
				)
			)
		)
		(property "Manufacturer" "Panasonic"
			(at 296.545 156.21 0)
			(effects
				(font
					(size 1.27 1.27)
					(thickness 0.15)
				)
				(justify left bottom)
				(hide yes)
			)
		)
		(property "MPN" "ERJ2GE0R00X"
			(at 296.545 153.67 0)
			(effects
				(font
					(size 1.27 1.27)
					(thickness 0.15)
				)
				(justify left bottom)
				(hide yes)
			)
		)
		(property "Val" "0R"
			(at 274.955 132.08 0)
			(effects
				(font
					(size 1.27 1.27)
					(thickness 0.15)
				)
			)
		)
		(property "License" "Apache-2.0"
			(at 296.545 158.75 0)
			(effects
				(font
					(size 1.27 1.27)
					(thickness 0.15)
				)
				(justify left bottom)
				(hide yes)
			)
		)
		(property "Author" "Antmicro"
			(at 296.545 161.29 0)
			(effects
				(font
					(size 1.27 1.27)
					(thickness 0.15)
				)
				(justify left bottom)
				(hide yes)
			)
		)
		(property "Tolerance" "~"
			(at 296.545 143.51 0)
			(effects
				(font
					(size 1.27 1.27)
				)
				(justify left bottom)
				(hide yes)
			)
		)
		(property "Current" "1A"
			(at 278.765 142.24 0)
			(effects
				(font
					(size 1.27 1.27)
					(thickness 0.15)
				)
				(hide yes)
			)
		)
		(pin "1"
		)
		(pin "2"
		)
		(instances
			(project "sodimm-ddr5-tester"
				(path ""
					(reference "R88")
					(unit 1)
				)
			)
		)
	)
	(symbol
		(lib_id "antmicroResistors0402:R_5k11_0402")
		(at 72.39 54.61 0)
		(mirror x)
		(unit 1)
		(exclude_from_sim no)
		(in_bom yes)
		(on_board yes)
		(dnp no)
		(property "Reference" "R69"
			(at 79.375 53.34 0)
			(effects
				(font
					(size 1.27 1.27)
				)
			)
		)
		(property "Value" "R_5k11_0402"
			(at 92.71 41.91 0)
			(effects
				(font
					(size 1.27 1.27)
					(thickness 0.15)
				)
				(justify left bottom)
				(hide yes)
			)
		)
		(property "Footprint" "antmicro-footprints:R_0402_1005Metric"
			(at 92.71 39.37 0)
			(effects
				(font
					(size 1.27 1.27)
					(thickness 0.15)
				)
				(justify left bottom)
				(hide yes)
			)
		)
		(property "Datasheet" "https://www.bourns.com/docs/product-datasheets/cr.pdf"
			(at 92.71 36.83 0)
			(effects
				(font
					(size 1.27 1.27)
					(thickness 0.15)
				)
				(justify left bottom)
				(hide yes)
			)
		)
		(property "Description" ""
			(at 72.39 54.61 0)
			(effects
				(font
					(size 1.27 1.27)
				)
			)
		)
		(property "Manufacturer" "Bourns"
			(at 92.71 31.75 0)
			(effects
				(font
					(size 1.27 1.27)
					(thickness 0.15)
				)
				(justify left bottom)
				(hide yes)
			)
		)
		(property "MPN" "CR0402-FX-5111GLF"
			(at 92.71 34.29 0)
			(effects
				(font
					(size 1.27 1.27)
					(thickness 0.15)
				)
				(justify left bottom)
				(hide yes)
			)
		)
		(property "Val" "5k11"
			(at 70.485 53.34 0)
			(effects
				(font
					(size 1.27 1.27)
					(thickness 0.15)
				)
			)
		)
		(property "License" "Apache-2.0"
			(at 92.71 29.21 0)
			(effects
				(font
					(size 1.27 1.27)
					(thickness 0.15)
				)
				(justify left bottom)
				(hide yes)
			)
		)
		(property "Author" "Antmicro"
			(at 92.71 26.67 0)
			(effects
				(font
					(size 1.27 1.27)
					(thickness 0.15)
				)
				(justify left bottom)
				(hide yes)
			)
		)
		(property "Tolerance" "1%"
			(at 92.71 44.45 0)
			(effects
				(font
					(size 1.27 1.27)
				)
				(justify left bottom)
				(hide yes)
			)
		)
		(pin "1"
		)
		(pin "2"
		)
		(instances
			(project "sodimm-ddr5-tester"
				(path ""
					(reference "R69")
					(unit 1)
				)
			)
		)
	)
	(symbol
		(lib_id "antmicropower:+3V3")
		(at 265.43 167.005 0)
		(unit 1)
		(exclude_from_sim no)
		(in_bom yes)
		(on_board yes)
		(dnp no)
		(property "Reference" "#PWR010"
			(at 265.43 170.815 0)
			(effects
				(font
					(size 1.27 1.27)
				)
				(hide yes)
			)
		)
		(property "Value" "+3V3"
			(at 262.255 164.465 0)
			(effects
				(font
					(size 1.27 1.27)
					(thickness 0.15)
				)
				(justify left bottom)
			)
		)
		(property "Footprint" ""
			(at 280.67 174.625 0)
			(effects
				(font
					(size 1.27 1.27)
					(thickness 0.15)
				)
				(justify left bottom)
				(hide yes)
			)
		)
		(property "Datasheet" ""
			(at 280.67 177.165 0)
			(effects
				(font
					(size 1.27 1.27)
					(thickness 0.15)
				)
				(justify left bottom)
				(hide yes)
			)
		)
		(property "Description" ""
			(at 265.43 167.005 0)
			(effects
				(font
					(size 1.27 1.27)
				)
			)
		)
		(property "Author" "Antmicro"
			(at 280.67 169.545 0)
			(effects
				(font
					(size 1.27 1.27)
					(thickness 0.15)
				)
				(justify left bottom)
				(hide yes)
			)
		)
		(property "License" "Apache-2.0"
			(at 280.67 172.085 0)
			(effects
				(font
					(size 1.27 1.27)
					(thickness 0.15)
				)
				(justify left bottom)
				(hide yes)
			)
		)
		(pin "1"
		)
		(instances
			(project "sodimm-ddr5-tester"
				(path ""
					(reference "#PWR010")
					(unit 1)
				)
			)
		)
	)
	(symbol
		(lib_id "antmicroCapacitors0402:C_100n_0402")
		(at 372.11 193.675 90)
		(unit 1)
		(exclude_from_sim no)
		(in_bom yes)
		(on_board yes)
		(dnp no)
		(fields_autoplaced yes)
		(property "Reference" "C238"
			(at 374.4341 190.298 90)
			(effects
				(font
					(size 1.27 1.27)
					(thickness 0.15)
				)
				(justify right)
			)
		)
		(property "Value" "C_100n_0402"
			(at 382.27 173.355 0)
			(effects
				(font
					(size 1.27 1.27)
					(thickness 0.15)
				)
				(justify left bottom)
				(hide yes)
			)
		)
		(property "Footprint" "antmicro-footprints:C_0402_1005Metric"
			(at 384.81 173.355 0)
			(effects
				(font
					(size 1.27 1.27)
					(thickness 0.15)
				)
				(justify left bottom)
				(hide yes)
			)
		)
		(property "Datasheet" "https://www.murata.com/products/productdetail?partno=GRM155R61H104KE14%23"
			(at 387.35 173.355 0)
			(effects
				(font
					(size 1.27 1.27)
					(thickness 0.15)
				)
				(justify left bottom)
				(hide yes)
			)
		)
		(property "Description" ""
			(at 372.11 193.675 0)
			(effects
				(font
					(size 1.27 1.27)
				)
			)
		)
		(property "MPN" "GRM155R61H104KE14D"
			(at 389.89 173.355 0)
			(effects
				(font
					(size 1.27 1.27)
					(thickness 0.15)
				)
				(justify left bottom)
				(hide yes)
			)
		)
		(property "Manufacturer" "Murata"
			(at 392.43 173.355 0)
			(effects
				(font
					(size 1.27 1.27)
					(thickness 0.15)
				)
				(justify left bottom)
				(hide yes)
			)
		)
		(property "License" "Apache-2.0"
			(at 394.97 173.355 0)
			(effects
				(font
					(size 1.27 1.27)
					(thickness 0.15)
				)
				(justify left bottom)
				(hide yes)
			)
		)
		(property "Author" "Antmicro"
			(at 397.51 173.355 0)
			(effects
				(font
					(size 1.27 1.27)
					(thickness 0.15)
				)
				(justify left bottom)
				(hide yes)
			)
		)
		(property "Val" "100n"
			(at 374.4341 192.8217 90)
			(effects
				(font
					(size 1.27 1.27)
					(thickness 0.15)
				)
				(justify right)
			)
		)
		(property "Voltage" "50V"
			(at 400.05 173.355 0)
			(effects
				(font
					(size 1.27 1.27)
				)
				(justify left bottom)
				(hide yes)
			)
		)
		(property "Dielectric" "X5R"
			(at 402.59 173.355 0)
			(effects
				(font
					(size 1.27 1.27)
				)
				(justify left bottom)
				(hide yes)
			)
		)
		(pin "1"
		)
		(pin "2"
		)
		(instances
			(project "sodimm-ddr5-tester"
				(path ""
					(reference "C238")
					(unit 1)
				)
			)
		)
	)
	(symbol
		(lib_id "antmicropower:GND")
		(at 360.045 175.26 0)
		(unit 1)
		(exclude_from_sim no)
		(in_bom yes)
		(on_board yes)
		(dnp no)
		(property "Reference" "#PWR012"
			(at 360.045 181.61 0)
			(effects
				(font
					(size 1.27 1.27)
				)
				(hide yes)
			)
		)
		(property "Value" "GND"
			(at 358.14 179.705 0)
			(effects
				(font
					(size 1.27 1.27)
					(thickness 0.15)
				)
				(justify left bottom)
			)
		)
		(property "Footprint" ""
			(at 368.935 182.88 0)
			(effects
				(font
					(size 1.27 1.27)
					(thickness 0.15)
				)
				(justify left bottom)
				(hide yes)
			)
		)
		(property "Datasheet" ""
			(at 368.935 187.96 0)
			(effects
				(font
					(size 1.27 1.27)
					(thickness 0.15)
				)
				(justify left bottom)
				(hide yes)
			)
		)
		(property "Description" ""
			(at 368.935 190.5 0)
			(effects
				(font
					(size 1.27 1.27)
				)
				(justify left bottom)
				(hide yes)
			)
		)
		(property "Author" "Antmicro"
			(at 368.935 182.88 0)
			(effects
				(font
					(size 1.27 1.27)
					(thickness 0.15)
				)
				(justify left bottom)
				(hide yes)
			)
		)
		(property "License" "Apache-2.0"
			(at 368.935 185.42 0)
			(effects
				(font
					(size 1.27 1.27)
					(thickness 0.15)
				)
				(justify left bottom)
				(hide yes)
			)
		)
		(pin "1"
		)
		(instances
			(project "sodimm-ddr5-tester"
				(path ""
					(reference "#PWR012")
					(unit 1)
				)
			)
		)
	)
	(symbol
		(lib_id "antmicroLogicTranslatorsLevelShifters:TXS0102DQER")
		(at 245.11 190.5 0)
		(unit 1)
		(exclude_from_sim no)
		(in_bom yes)
		(on_board yes)
		(dnp no)
		(fields_autoplaced yes)
		(property "Reference" "U33"
			(at 254 186.055 0)
			(effects
				(font
					(size 1.27 1.27)
					(thickness 0.15)
				)
			)
		)
		(property "Value" "TXS0102DQER"
			(at 254 188.595 0)
			(effects
				(font
					(size 1.27 1.27)
					(thickness 0.15)
				)
			)
		)
		(property "Footprint" "antmicro-footprints:X2SON8_1.4x1x0.32mm_P0.35mm"
			(at 278.13 200.66 0)
			(effects
				(font
					(size 1.27 1.27)
					(thickness 0.15)
				)
				(justify left bottom)
				(hide yes)
			)
		)
		(property "Datasheet" "https://www.ti.com/lit/ds/symlink/txs0102.pdf?ts=1637914596981&ref_url=https%253A%252F%252Fwww.ti.com%252Fstore%252Fti%252Fen%252Fp%252Fproduct%252F%253Fp%253DTXS0102DCTR%2526keyMatch%253DTXS0102DCTR%2526tisearch%253Dsearch-everything%2526usecase%253DOPN"
			(at 278.13 203.2 0)
			(effects
				(font
					(size 1.27 1.27)
					(thickness 0.15)
				)
				(justify left bottom)
				(hide yes)
			)
		)
		(property "Description" ""
			(at 245.11 190.5 0)
			(effects
				(font
					(size 1.27 1.27)
				)
			)
		)
		(property "MPN" "TXS0102DQER"
			(at 278.13 205.74 0)
			(effects
				(font
					(size 1.27 1.27)
					(thickness 0.15)
				)
				(justify left bottom)
				(hide yes)
			)
		)
		(property "Manufacturer" "Texas Instruments"
			(at 278.13 208.28 0)
			(effects
				(font
					(size 1.27 1.27)
					(thickness 0.15)
				)
				(justify left bottom)
				(hide yes)
			)
		)
		(property "Author" "Antmicro"
			(at 278.13 210.82 0)
			(effects
				(font
					(size 1.27 1.27)
					(thickness 0.15)
				)
				(justify left bottom)
				(hide yes)
			)
		)
		(property "License" "Apache-2.0"
			(at 278.13 213.36 0)
			(effects
				(font
					(size 1.27 1.27)
					(thickness 0.15)
				)
				(justify left bottom)
				(hide yes)
			)
		)
		(pin "3"
		)
		(pin "8"
		)
		(pin "7"
		)
		(pin "4"
		)
		(pin "2"
		)
		(pin "1"
		)
		(pin "5"
		)
		(pin "6"
		)
		(instances
			(project "sodimm-ddr5-tester"
				(path ""
					(reference "U33")
					(unit 1)
				)
			)
		)
	)
	(symbol
		(lib_id "antmicropower:GND")
		(at 243.84 149.86 0)
		(unit 1)
		(exclude_from_sim no)
		(in_bom yes)
		(on_board yes)
		(dnp no)
		(property "Reference" "#PWR0206"
			(at 243.84 156.21 0)
			(effects
				(font
					(size 1.27 1.27)
				)
				(hide yes)
			)
		)
		(property "Value" "GND"
			(at 241.935 154.305 0)
			(effects
				(font
					(size 1.27 1.27)
					(thickness 0.15)
				)
				(justify left bottom)
			)
		)
		(property "Footprint" ""
			(at 252.73 157.48 0)
			(effects
				(font
					(size 1.27 1.27)
					(thickness 0.15)
				)
				(justify left bottom)
				(hide yes)
			)
		)
		(property "Datasheet" ""
			(at 252.73 162.56 0)
			(effects
				(font
					(size 1.27 1.27)
					(thickness 0.15)
				)
				(justify left bottom)
				(hide yes)
			)
		)
		(property "Description" ""
			(at 252.73 165.1 0)
			(effects
				(font
					(size 1.27 1.27)
				)
				(justify left bottom)
				(hide yes)
			)
		)
		(property "Author" "Antmicro"
			(at 252.73 157.48 0)
			(effects
				(font
					(size 1.27 1.27)
					(thickness 0.15)
				)
				(justify left bottom)
				(hide yes)
			)
		)
		(property "License" "Apache-2.0"
			(at 252.73 160.02 0)
			(effects
				(font
					(size 1.27 1.27)
					(thickness 0.15)
				)
				(justify left bottom)
				(hide yes)
			)
		)
		(pin "1"
		)
		(instances
			(project "sodimm-ddr5-tester"
				(path ""
					(reference "#PWR0206")
					(unit 1)
				)
			)
		)
	)
	(symbol
		(lib_id "antmicroLEDIndicationDiscrete:LED_G_0603_KP-1608CGCK")
		(at 80.645 239.395 180)
		(unit 1)
		(exclude_from_sim no)
		(in_bom yes)
		(on_board yes)
		(dnp no)
		(property "Reference" "D11"
			(at 76.835 236.855 0)
			(effects
				(font
					(size 1.27 1.27)
				)
			)
		)
		(property "Value" "LED_G_0603_KP-1608CGCK"
			(at 54.61 239.395 0)
			(effects
				(font
					(size 1.27 1.27)
					(thickness 0.15)
				)
			)
		)
		(property "Footprint" "antmicro-footprints:LED_0603_1608Metric_G"
			(at 57.785 229.235 0)
			(effects
				(font
					(size 1.27 1.27)
					(thickness 0.15)
				)
				(justify left bottom)
				(hide yes)
			)
		)
		(property "Datasheet" "http://www.farnell.com/datasheets/2045956.pdf"
			(at 57.785 226.695 0)
			(effects
				(font
					(size 1.27 1.27)
					(thickness 0.15)
				)
				(justify left bottom)
				(hide yes)
			)
		)
		(property "Description" ""
			(at 80.645 239.395 0)
			(effects
				(font
					(size 1.27 1.27)
				)
			)
		)
		(property "MPN" "KP-1608CGCK"
			(at 76.2 236.855 0)
			(effects
				(font
					(size 1.27 1.27)
					(thickness 0.15)
				)
				(hide yes)
			)
		)
		(property "Manufacturer" "Kingbright"
			(at 57.785 221.615 0)
			(effects
				(font
					(size 1.27 1.27)
					(thickness 0.15)
				)
				(justify left bottom)
				(hide yes)
			)
		)
		(property "Author" "Antmicro"
			(at 57.785 219.075 0)
			(effects
				(font
					(size 1.27 1.27)
					(thickness 0.15)
				)
				(justify left bottom)
				(hide yes)
			)
		)
		(property "License" "Apache-2.0"
			(at 57.785 216.535 0)
			(effects
				(font
					(size 1.27 1.27)
					(thickness 0.15)
				)
				(justify left bottom)
				(hide yes)
			)
		)
		(pin "1"
		)
		(pin "2"
		)
		(instances
			(project "sodimm-ddr5-tester"
				(path ""
					(reference "D11")
					(unit 1)
				)
			)
		)
	)
	(symbol
		(lib_id "antmicroResistors0402:R_22R_0402")
		(at 179.705 146.05 0)
		(unit 1)
		(exclude_from_sim no)
		(in_bom no)
		(on_board yes)
		(dnp yes)
		(property "Reference" "R59"
			(at 186.69 144.78 0)
			(effects
				(font
					(size 1.27 1.27)
				)
			)
		)
		(property "Value" "R_22R_0402"
			(at 200.025 158.75 0)
			(effects
				(font
					(size 1.27 1.27)
					(thickness 0.15)
				)
				(justify left bottom)
				(hide yes)
			)
		)
		(property "Footprint" "antmicro-footprints:R_0402_1005Metric"
			(at 200.025 161.29 0)
			(effects
				(font
					(size 1.27 1.27)
					(thickness 0.15)
				)
				(justify left bottom)
				(hide yes)
			)
		)
		(property "Datasheet" "https://www.bourns.com/docs/product-datasheets/cr.pdf"
			(at 200.025 163.83 0)
			(effects
				(font
					(size 1.27 1.27)
					(thickness 0.15)
				)
				(justify left bottom)
				(hide yes)
			)
		)
		(property "Description" ""
			(at 179.705 146.05 0)
			(effects
				(font
					(size 1.27 1.27)
				)
			)
		)
		(property "Manufacturer" "Bourns"
			(at 200.025 168.91 0)
			(effects
				(font
					(size 1.27 1.27)
					(thickness 0.15)
				)
				(justify left bottom)
				(hide yes)
			)
		)
		(property "MPN" "CR0402-FX-22R0GLF"
			(at 200.025 166.37 0)
			(effects
				(font
					(size 1.27 1.27)
					(thickness 0.15)
				)
				(justify left bottom)
				(hide yes)
			)
		)
		(property "Val" "22R"
			(at 177.8 144.78 0)
			(effects
				(font
					(size 1.27 1.27)
					(thickness 0.15)
				)
			)
		)
		(property "License" "Apache-2.0"
			(at 200.025 171.45 0)
			(effects
				(font
					(size 1.27 1.27)
					(thickness 0.15)
				)
				(justify left bottom)
				(hide yes)
			)
		)
		(property "Author" "Antmicro"
			(at 200.025 173.99 0)
			(effects
				(font
					(size 1.27 1.27)
					(thickness 0.15)
				)
				(justify left bottom)
				(hide yes)
			)
		)
		(property "Tolerance" "1%"
			(at 200.025 156.21 0)
			(effects
				(font
					(size 1.27 1.27)
				)
				(justify left bottom)
				(hide yes)
			)
		)
		(pin "1"
		)
		(pin "2"
		)
		(instances
			(project "sodimm-ddr5-tester"
				(path ""
					(reference "R59")
					(unit 1)
				)
			)
		)
	)
	(symbol
		(lib_id "antmicropower:PWR_FLAG")
		(at 71.247 116.84 0)
		(unit 1)
		(exclude_from_sim no)
		(in_bom yes)
		(on_board yes)
		(dnp no)
		(fields_autoplaced yes)
		(property "Reference" "#FLG0103"
			(at 71.247 114.935 0)
			(effects
				(font
					(size 1.27 1.27)
				)
				(hide yes)
			)
		)
		(property "Value" "PWR_FLAG"
			(at 71.247 113.2642 0)
			(effects
				(font
					(size 1.27 1.27)
				)
			)
		)
		(property "Footprint" ""
			(at 71.247 116.84 0)
			(effects
				(font
					(size 1.27 1.27)
				)
				(hide yes)
			)
		)
		(property "Datasheet" ""
			(at 71.247 116.84 0)
			(effects
				(font
					(size 1.27 1.27)
				)
				(hide yes)
			)
		)
		(property "Description" ""
			(at 71.247 116.84 0)
			(effects
				(font
					(size 1.27 1.27)
				)
			)
		)
		(pin "1"
		)
		(instances
			(project "sodimm-ddr5-tester"
				(path ""
					(reference "#FLG0103")
					(unit 1)
				)
			)
		)
	)
	(symbol
		(lib_id "antmicroTestPoints:TP_1mm_SMD")
		(at 288.29 275.59 270)
		(unit 1)
		(exclude_from_sim no)
		(in_bom yes)
		(on_board yes)
		(dnp no)
		(property "Reference" "TP53"
			(at 288.29 280.5628 90)
			(effects
				(font
					(size 1.27 1.27)
				)
			)
		)
		(property "Value" "TP_1mm_SMD"
			(at 280.67 290.83 0)
			(effects
				(font
					(size 1.27 1.27)
					(thickness 0.15)
				)
				(justify left bottom)
				(hide yes)
			)
		)
		(property "Footprint" "antmicro-footprints:TP_SMD_1mm"
			(at 278.13 290.83 0)
			(effects
				(font
					(size 1.27 1.27)
					(thickness 0.15)
				)
				(justify left bottom)
				(hide yes)
			)
		)
		(property "Datasheet" ""
			(at 275.59 290.83 0)
			(effects
				(font
					(size 1.27 1.27)
					(thickness 0.15)
				)
				(justify left bottom)
				(hide yes)
			)
		)
		(property "Description" ""
			(at 288.29 275.59 0)
			(effects
				(font
					(size 1.27 1.27)
				)
			)
		)
		(property "MPN" ""
			(at 288.29 275.59 0)
			(effects
				(font
					(size 1.27 1.27)
				)
				(hide yes)
			)
		)
		(property "Manufacturer" ""
			(at 288.29 275.59 0)
			(effects
				(font
					(size 1.27 1.27)
				)
				(hide yes)
			)
		)
		(property "Author" "Antmicro"
			(at 273.05 290.83 0)
			(effects
				(font
					(size 1.27 1.27)
					(thickness 0.15)
				)
				(justify left bottom)
				(hide yes)
			)
		)
		(property "License" "Apache-2.0"
			(at 270.51 290.83 0)
			(effects
				(font
					(size 1.27 1.27)
					(thickness 0.15)
				)
				(justify left bottom)
				(hide yes)
			)
		)
		(pin "1"
		)
		(instances
			(project "sodimm-ddr5-tester"
				(path ""
					(reference "TP53")
					(unit 1)
				)
			)
		)
	)
	(symbol
		(lib_id "antmicroLEDIndicationDiscrete:LED_G_0603_KP-1608CGCK")
		(at 80.645 245.745 180)
		(unit 1)
		(exclude_from_sim no)
		(in_bom yes)
		(on_board yes)
		(dnp no)
		(property "Reference" "D12"
			(at 76.835 243.205 0)
			(effects
				(font
					(size 1.27 1.27)
				)
			)
		)
		(property "Value" "LED_G_0603_KP-1608CGCK"
			(at 54.61 245.745 0)
			(effects
				(font
					(size 1.27 1.27)
					(thickness 0.15)
				)
			)
		)
		(property "Footprint" "antmicro-footprints:LED_0603_1608Metric_G"
			(at 57.785 235.585 0)
			(effects
				(font
					(size 1.27 1.27)
					(thickness 0.15)
				)
				(justify left bottom)
				(hide yes)
			)
		)
		(property "Datasheet" "http://www.farnell.com/datasheets/2045956.pdf"
			(at 57.785 233.045 0)
			(effects
				(font
					(size 1.27 1.27)
					(thickness 0.15)
				)
				(justify left bottom)
				(hide yes)
			)
		)
		(property "Description" ""
			(at 80.645 245.745 0)
			(effects
				(font
					(size 1.27 1.27)
				)
			)
		)
		(property "MPN" "KP-1608CGCK"
			(at 76.2 243.205 0)
			(effects
				(font
					(size 1.27 1.27)
					(thickness 0.15)
				)
				(hide yes)
			)
		)
		(property "Manufacturer" "Kingbright"
			(at 57.785 227.965 0)
			(effects
				(font
					(size 1.27 1.27)
					(thickness 0.15)
				)
				(justify left bottom)
				(hide yes)
			)
		)
		(property "Author" "Antmicro"
			(at 57.785 225.425 0)
			(effects
				(font
					(size 1.27 1.27)
					(thickness 0.15)
				)
				(justify left bottom)
				(hide yes)
			)
		)
		(property "License" "Apache-2.0"
			(at 57.785 222.885 0)
			(effects
				(font
					(size 1.27 1.27)
					(thickness 0.15)
				)
				(justify left bottom)
				(hide yes)
			)
		)
		(pin "1"
		)
		(pin "2"
		)
		(instances
			(project "sodimm-ddr5-tester"
				(path ""
					(reference "D12")
					(unit 1)
				)
			)
		)
	)
	(symbol
		(lib_id "antmicropower:+3V3_AON")
		(at 371.602 127 0)
		(mirror y)
		(unit 1)
		(exclude_from_sim no)
		(in_bom yes)
		(on_board yes)
		(dnp no)
		(property "Reference" "#PWR0194"
			(at 371.602 130.81 0)
			(effects
				(font
					(size 1.27 1.27)
				)
				(hide yes)
			)
		)
		(property "Value" "+3V3_AON"
			(at 377.317 123.825 0)
			(effects
				(font
					(size 1.27 1.27)
				)
			)
		)
		(property "Footprint" ""
			(at 371.602 127 0)
			(effects
				(font
					(size 1.27 1.27)
				)
				(hide yes)
			)
		)
		(property "Datasheet" ""
			(at 371.602 127 0)
			(effects
				(font
					(size 1.27 1.27)
				)
				(hide yes)
			)
		)
		(property "Description" ""
			(at 371.602 127 0)
			(effects
				(font
					(size 1.27 1.27)
				)
			)
		)
		(pin "1"
		)
		(instances
			(project "sodimm-ddr5-tester"
				(path ""
					(reference "#PWR0194")
					(unit 1)
				)
			)
		)
	)
	(symbol
		(lib_id "antmicroCapacitors0402:C_100n_0402")
		(at 361.315 109.855 90)
		(unit 1)
		(exclude_from_sim no)
		(in_bom yes)
		(on_board yes)
		(dnp no)
		(fields_autoplaced yes)
		(property "Reference" "C121"
			(at 363.6391 106.478 90)
			(effects
				(font
					(size 1.27 1.27)
					(thickness 0.15)
				)
				(justify right)
			)
		)
		(property "Value" "C_100n_0402"
			(at 371.475 89.535 0)
			(effects
				(font
					(size 1.27 1.27)
					(thickness 0.15)
				)
				(justify left bottom)
				(hide yes)
			)
		)
		(property "Footprint" "antmicro-footprints:C_0402_1005Metric"
			(at 374.015 89.535 0)
			(effects
				(font
					(size 1.27 1.27)
					(thickness 0.15)
				)
				(justify left bottom)
				(hide yes)
			)
		)
		(property "Datasheet" "https://www.murata.com/products/productdetail?partno=GRM155R61H104KE14%23"
			(at 376.555 89.535 0)
			(effects
				(font
					(size 1.27 1.27)
					(thickness 0.15)
				)
				(justify left bottom)
				(hide yes)
			)
		)
		(property "Description" ""
			(at 361.315 109.855 0)
			(effects
				(font
					(size 1.27 1.27)
				)
			)
		)
		(property "MPN" "GRM155R61H104KE14D"
			(at 379.095 89.535 0)
			(effects
				(font
					(size 1.27 1.27)
					(thickness 0.15)
				)
				(justify left bottom)
				(hide yes)
			)
		)
		(property "Manufacturer" "Murata"
			(at 381.635 89.535 0)
			(effects
				(font
					(size 1.27 1.27)
					(thickness 0.15)
				)
				(justify left bottom)
				(hide yes)
			)
		)
		(property "License" "Apache-2.0"
			(at 384.175 89.535 0)
			(effects
				(font
					(size 1.27 1.27)
					(thickness 0.15)
				)
				(justify left bottom)
				(hide yes)
			)
		)
		(property "Author" "Antmicro"
			(at 386.715 89.535 0)
			(effects
				(font
					(size 1.27 1.27)
					(thickness 0.15)
				)
				(justify left bottom)
				(hide yes)
			)
		)
		(property "Val" "100n"
			(at 363.6391 109.0017 90)
			(effects
				(font
					(size 1.27 1.27)
					(thickness 0.15)
				)
				(justify right)
			)
		)
		(property "Voltage" "50V"
			(at 389.255 89.535 0)
			(effects
				(font
					(size 1.27 1.27)
				)
				(justify left bottom)
				(hide yes)
			)
		)
		(property "Dielectric" "X5R"
			(at 391.795 89.535 0)
			(effects
				(font
					(size 1.27 1.27)
				)
				(justify left bottom)
				(hide yes)
			)
		)
		(pin "1"
		)
		(pin "2"
		)
		(instances
			(project "sodimm-ddr5-tester"
				(path ""
					(reference "C121")
					(unit 1)
				)
			)
		)
	)
	(symbol
		(lib_id "antmicroTestPoints:TP_1mm_SMD")
		(at 219.71 275.59 270)
		(unit 1)
		(exclude_from_sim no)
		(in_bom yes)
		(on_board yes)
		(dnp no)
		(property "Reference" "TP42"
			(at 219.71 280.5628 90)
			(effects
				(font
					(size 1.27 1.27)
				)
			)
		)
		(property "Value" "TP_1mm_SMD"
			(at 212.09 290.83 0)
			(effects
				(font
					(size 1.27 1.27)
					(thickness 0.15)
				)
				(justify left bottom)
				(hide yes)
			)
		)
		(property "Footprint" "antmicro-footprints:TP_SMD_1mm"
			(at 209.55 290.83 0)
			(effects
				(font
					(size 1.27 1.27)
					(thickness 0.15)
				)
				(justify left bottom)
				(hide yes)
			)
		)
		(property "Datasheet" ""
			(at 207.01 290.83 0)
			(effects
				(font
					(size 1.27 1.27)
					(thickness 0.15)
				)
				(justify left bottom)
				(hide yes)
			)
		)
		(property "Description" ""
			(at 219.71 275.59 0)
			(effects
				(font
					(size 1.27 1.27)
				)
			)
		)
		(property "MPN" ""
			(at 219.71 275.59 0)
			(effects
				(font
					(size 1.27 1.27)
				)
				(hide yes)
			)
		)
		(property "Manufacturer" ""
			(at 219.71 275.59 0)
			(effects
				(font
					(size 1.27 1.27)
				)
				(hide yes)
			)
		)
		(property "Author" "Antmicro"
			(at 204.47 290.83 0)
			(effects
				(font
					(size 1.27 1.27)
					(thickness 0.15)
				)
				(justify left bottom)
				(hide yes)
			)
		)
		(property "License" "Apache-2.0"
			(at 201.93 290.83 0)
			(effects
				(font
					(size 1.27 1.27)
					(thickness 0.15)
				)
				(justify left bottom)
				(hide yes)
			)
		)
		(pin "1"
		)
		(instances
			(project "sodimm-ddr5-tester"
				(path ""
					(reference "TP42")
					(unit 1)
				)
			)
		)
	)
	(symbol
		(lib_name "BAT54-02V-G3-08_1")
		(lib_id "antmicroDiodesRectifiersSingle:BAT54-02V-G3-08")
		(at 279.4 143.51 0)
		(unit 1)
		(exclude_from_sim no)
		(in_bom yes)
		(on_board yes)
		(dnp no)
		(property "Reference" "D15"
			(at 281.94 147.32 0)
			(effects
				(font
					(size 1.27 1.27)
					(thickness 0.15)
				)
			)
		)
		(property "Value" "BAT54-02V-G3-08"
			(at 300.99 158.75 0)
			(effects
				(font
					(size 1.27 1.27)
					(thickness 0.15)
				)
				(justify left bottom)
				(hide yes)
			)
		)
		(property "Footprint" "antmicro-footprints:SOD-523"
			(at 300.99 153.67 0)
			(effects
				(font
					(size 1.27 1.27)
					(thickness 0.15)
				)
				(justify left bottom)
				(hide yes)
			)
		)
		(property "Datasheet" "https://www.vishay.com/docs/85633/bat5402v.pdf"
			(at 300.99 156.21 0)
			(effects
				(font
					(size 1.27 1.27)
					(thickness 0.15)
				)
				(justify left bottom)
				(hide yes)
			)
		)
		(property "Description" "Small Signal Schottky Diode, Single, 30 V, 200 mA, 800 mV, 600 mA, 125 °C"
			(at 300.99 168.91 0)
			(effects
				(font
					(size 1.27 1.27)
				)
				(justify left bottom)
				(hide yes)
			)
		)
		(property "MPN" "BAT54-02V-G3-08"
			(at 281.94 149.352 0)
			(effects
				(font
					(size 1.27 1.27)
					(thickness 0.15)
				)
			)
		)
		(property "Manufacturer" "Vishay"
			(at 300.99 161.29 0)
			(effects
				(font
					(size 1.27 1.27)
					(thickness 0.15)
				)
				(justify left bottom)
				(hide yes)
			)
		)
		(property "Author" "Antmicro"
			(at 300.99 163.83 0)
			(effects
				(font
					(size 1.27 1.27)
					(thickness 0.15)
				)
				(justify left bottom)
				(hide yes)
			)
		)
		(property "License" "Apache-2.0"
			(at 300.99 166.37 0)
			(effects
				(font
					(size 1.27 1.27)
					(thickness 0.15)
				)
				(justify left bottom)
				(hide yes)
			)
		)
		(pin "2"
		)
		(pin "1"
		)
		(instances
			(project ""
				(path ""
					(reference "D15")
					(unit 1)
				)
			)
		)
	)
	(symbol
		(lib_id "antmicropower:GND")
		(at 361.315 111.125 0)
		(unit 1)
		(exclude_from_sim no)
		(in_bom yes)
		(on_board yes)
		(dnp no)
		(property "Reference" "#PWR0196"
			(at 361.315 117.475 0)
			(effects
				(font
					(size 1.27 1.27)
				)
				(hide yes)
			)
		)
		(property "Value" "GND"
			(at 359.41 115.57 0)
			(effects
				(font
					(size 1.27 1.27)
					(thickness 0.15)
				)
				(justify left bottom)
			)
		)
		(property "Footprint" ""
			(at 370.205 118.745 0)
			(effects
				(font
					(size 1.27 1.27)
					(thickness 0.15)
				)
				(justify left bottom)
				(hide yes)
			)
		)
		(property "Datasheet" ""
			(at 370.205 123.825 0)
			(effects
				(font
					(size 1.27 1.27)
					(thickness 0.15)
				)
				(justify left bottom)
				(hide yes)
			)
		)
		(property "Description" ""
			(at 370.205 126.365 0)
			(effects
				(font
					(size 1.27 1.27)
				)
				(justify left bottom)
				(hide yes)
			)
		)
		(property "Author" "Antmicro"
			(at 370.205 118.745 0)
			(effects
				(font
					(size 1.27 1.27)
					(thickness 0.15)
				)
				(justify left bottom)
				(hide yes)
			)
		)
		(property "License" "Apache-2.0"
			(at 370.205 121.285 0)
			(effects
				(font
					(size 1.27 1.27)
					(thickness 0.15)
				)
				(justify left bottom)
				(hide yes)
			)
		)
		(pin "1"
		)
		(instances
			(project "sodimm-ddr5-tester"
				(path ""
					(reference "#PWR0196")
					(unit 1)
				)
			)
		)
	)
	(symbol
		(lib_id "antmicropower:GND")
		(at 58.547 147.32 0)
		(unit 1)
		(exclude_from_sim no)
		(in_bom yes)
		(on_board yes)
		(dnp no)
		(fields_autoplaced yes)
		(property "Reference" "#PWR0257"
			(at 58.547 153.67 0)
			(effects
				(font
					(size 1.27 1.27)
				)
				(hide yes)
			)
		)
		(property "Value" "GND"
			(at 60.96 148.59 0)
			(effects
				(font
					(size 1.27 1.27)
					(thickness 0.15)
				)
				(justify left)
			)
		)
		(property "Footprint" ""
			(at 67.437 154.94 0)
			(effects
				(font
					(size 1.27 1.27)
					(thickness 0.15)
				)
				(justify left bottom)
				(hide yes)
			)
		)
		(property "Datasheet" ""
			(at 67.437 160.02 0)
			(effects
				(font
					(size 1.27 1.27)
					(thickness 0.15)
				)
				(justify left bottom)
				(hide yes)
			)
		)
		(property "Description" ""
			(at 67.437 162.56 0)
			(effects
				(font
					(size 1.27 1.27)
				)
				(justify left bottom)
				(hide yes)
			)
		)
		(property "Author" "Antmicro"
			(at 67.437 154.94 0)
			(effects
				(font
					(size 1.27 1.27)
					(thickness 0.15)
				)
				(justify left bottom)
				(hide yes)
			)
		)
		(property "License" "Apache-2.0"
			(at 67.437 157.48 0)
			(effects
				(font
					(size 1.27 1.27)
					(thickness 0.15)
				)
				(justify left bottom)
				(hide yes)
			)
		)
		(pin "1"
		)
		(instances
			(project "sodimm-ddr5-tester"
				(path ""
					(reference "#PWR0257")
					(unit 1)
				)
			)
		)
	)
	(symbol
		(lib_id "antmicroCapacitors0402:C_100n_0402")
		(at 156.21 231.14 90)
		(unit 1)
		(exclude_from_sim no)
		(in_bom yes)
		(on_board yes)
		(dnp no)
		(fields_autoplaced yes)
		(property "Reference" "C128"
			(at 158.5341 227.763 90)
			(effects
				(font
					(size 1.27 1.27)
					(thickness 0.15)
				)
				(justify right)
			)
		)
		(property "Value" "C_100n_0402"
			(at 166.37 210.82 0)
			(effects
				(font
					(size 1.27 1.27)
					(thickness 0.15)
				)
				(justify left bottom)
				(hide yes)
			)
		)
		(property "Footprint" "antmicro-footprints:C_0402_1005Metric"
			(at 168.91 210.82 0)
			(effects
				(font
					(size 1.27 1.27)
					(thickness 0.15)
				)
				(justify left bottom)
				(hide yes)
			)
		)
		(property "Datasheet" "https://www.murata.com/products/productdetail?partno=GRM155R61H104KE14%23"
			(at 171.45 210.82 0)
			(effects
				(font
					(size 1.27 1.27)
					(thickness 0.15)
				)
				(justify left bottom)
				(hide yes)
			)
		)
		(property "Description" ""
			(at 156.21 231.14 0)
			(effects
				(font
					(size 1.27 1.27)
				)
			)
		)
		(property "MPN" "GRM155R61H104KE14D"
			(at 173.99 210.82 0)
			(effects
				(font
					(size 1.27 1.27)
					(thickness 0.15)
				)
				(justify left bottom)
				(hide yes)
			)
		)
		(property "Manufacturer" "Murata"
			(at 176.53 210.82 0)
			(effects
				(font
					(size 1.27 1.27)
					(thickness 0.15)
				)
				(justify left bottom)
				(hide yes)
			)
		)
		(property "License" "Apache-2.0"
			(at 179.07 210.82 0)
			(effects
				(font
					(size 1.27 1.27)
					(thickness 0.15)
				)
				(justify left bottom)
				(hide yes)
			)
		)
		(property "Author" "Antmicro"
			(at 181.61 210.82 0)
			(effects
				(font
					(size 1.27 1.27)
					(thickness 0.15)
				)
				(justify left bottom)
				(hide yes)
			)
		)
		(property "Val" "100n"
			(at 158.5341 230.2867 90)
			(effects
				(font
					(size 1.27 1.27)
					(thickness 0.15)
				)
				(justify right)
			)
		)
		(property "Voltage" "50V"
			(at 184.15 210.82 0)
			(effects
				(font
					(size 1.27 1.27)
				)
				(justify left bottom)
				(hide yes)
			)
		)
		(property "Dielectric" "X5R"
			(at 186.69 210.82 0)
			(effects
				(font
					(size 1.27 1.27)
				)
				(justify left bottom)
				(hide yes)
			)
		)
		(pin "1"
		)
		(pin "2"
		)
		(instances
			(project "sodimm-ddr5-tester"
				(path ""
					(reference "C128")
					(unit 1)
				)
			)
		)
	)
	(symbol
		(lib_id "antmicroResonators:Resonator_12MHz_ABM8G")
		(at 89.535 180.34 0)
		(unit 1)
		(exclude_from_sim no)
		(in_bom yes)
		(on_board yes)
		(dnp no)
		(fields_autoplaced yes)
		(property "Reference" "Y1"
			(at 93.345 174.115 0)
			(effects
				(font
					(size 1.27 1.27)
					(thickness 0.15)
				)
			)
		)
		(property "Value" "Resonator_12MHz_ABM8G"
			(at 104.775 193.04 0)
			(effects
				(font
					(size 1.27 1.27)
					(thickness 0.15)
				)
				(justify left bottom)
				(hide yes)
			)
		)
		(property "Footprint" "antmicro-footprints:Resonator_SMD_Abracon_ABM8G_3.2x2.5mm"
			(at 104.775 195.58 0)
			(effects
				(font
					(size 1.27 1.27)
					(thickness 0.15)
				)
				(justify left bottom)
				(hide yes)
			)
		)
		(property "Datasheet" "https://abracon.com/Resonators/ABM8G.pdf"
			(at 104.775 198.12 0)
			(effects
				(font
					(size 1.27 1.27)
					(thickness 0.15)
				)
				(justify left bottom)
				(hide yes)
			)
		)
		(property "Description" ""
			(at 89.535 180.34 0)
			(effects
				(font
					(size 1.27 1.27)
				)
			)
		)
		(property "MPN" "ABM8G-12.000MHZ-18-D2Y-T"
			(at 104.775 187.96 0)
			(effects
				(font
					(size 1.27 1.27)
					(thickness 0.15)
				)
				(justify left bottom)
				(hide yes)
			)
		)
		(property "Manufacturer" "Abracon"
			(at 104.775 200.66 0)
			(effects
				(font
					(size 1.27 1.27)
					(thickness 0.15)
				)
				(justify left bottom)
				(hide yes)
			)
		)
		(property "Author" "Antmicro"
			(at 104.775 203.2 0)
			(effects
				(font
					(size 1.27 1.27)
					(thickness 0.15)
				)
				(justify left bottom)
				(hide yes)
			)
		)
		(property "License" "Apache-2.0"
			(at 104.775 205.74 0)
			(effects
				(font
					(size 1.27 1.27)
					(thickness 0.15)
				)
				(justify left bottom)
				(hide yes)
			)
		)
		(property "Val" "12 MHz"
			(at 93.345 176.6387 0)
			(effects
				(font
					(size 1.27 1.27)
					(thickness 0.15)
				)
			)
		)
		(pin "1"
		)
		(pin "2"
		)
		(pin "3"
		)
		(pin "4"
		)
		(instances
			(project "sodimm-ddr5-tester"
				(path ""
					(reference "Y1")
					(unit 1)
				)
			)
		)
	)
	(symbol
		(lib_id "antmicropower:PWR_FLAG")
		(at 136.525 44.45 0)
		(unit 1)
		(exclude_from_sim no)
		(in_bom yes)
		(on_board yes)
		(dnp no)
		(property "Reference" "#FLG01"
			(at 136.525 42.545 0)
			(effects
				(font
					(size 1.27 1.27)
				)
				(hide yes)
			)
		)
		(property "Value" "PWR_FLAG"
			(at 136.525 40.64 0)
			(effects
				(font
					(size 1.27 1.27)
				)
			)
		)
		(property "Footprint" ""
			(at 136.525 44.45 0)
			(effects
				(font
					(size 1.27 1.27)
				)
				(hide yes)
			)
		)
		(property "Datasheet" ""
			(at 136.525 44.45 0)
			(effects
				(font
					(size 1.27 1.27)
				)
				(hide yes)
			)
		)
		(property "Description" ""
			(at 136.525 44.45 0)
			(effects
				(font
					(size 1.27 1.27)
				)
			)
		)
		(pin "1"
		)
		(instances
			(project "sodimm-ddr5-tester"
				(path ""
					(reference "#FLG01")
					(unit 1)
				)
			)
		)
	)
	(symbol
		(lib_id "antmicropower:PWR_FLAG")
		(at 66.802 138.43 0)
		(unit 1)
		(exclude_from_sim no)
		(in_bom yes)
		(on_board yes)
		(dnp no)
		(fields_autoplaced yes)
		(property "Reference" "#FLG0101"
			(at 66.802 136.525 0)
			(effects
				(font
					(size 1.27 1.27)
				)
				(hide yes)
			)
		)
		(property "Value" "PWR_FLAG"
			(at 66.802 134.8542 0)
			(effects
				(font
					(size 1.27 1.27)
				)
			)
		)
		(property "Footprint" ""
			(at 66.802 138.43 0)
			(effects
				(font
					(size 1.27 1.27)
				)
				(hide yes)
			)
		)
		(property "Datasheet" ""
			(at 66.802 138.43 0)
			(effects
				(font
					(size 1.27 1.27)
				)
				(hide yes)
			)
		)
		(property "Description" ""
			(at 66.802 138.43 0)
			(effects
				(font
					(size 1.27 1.27)
				)
			)
		)
		(pin "1"
		)
		(instances
			(project "sodimm-ddr5-tester"
				(path ""
					(reference "#FLG0101")
					(unit 1)
				)
			)
		)
	)
	(symbol
		(lib_id "antmicroCapacitors0402:C_10u_6.3V_0402")
		(at 136.525 54.61 90)
		(unit 1)
		(exclude_from_sim no)
		(in_bom yes)
		(on_board yes)
		(dnp no)
		(fields_autoplaced yes)
		(property "Reference" "C113"
			(at 138.8491 51.233 90)
			(effects
				(font
					(size 1.27 1.27)
					(thickness 0.15)
				)
				(justify right)
			)
		)
		(property "Value" "C_10u_6.3V_0402"
			(at 146.685 34.29 0)
			(effects
				(font
					(size 1.27 1.27)
					(thickness 0.15)
				)
				(justify left bottom)
				(hide yes)
			)
		)
		(property "Footprint" "antmicro-footprints:C_0402_1005Metric"
			(at 149.225 34.29 0)
			(effects
				(font
					(size 1.27 1.27)
					(thickness 0.15)
				)
				(justify left bottom)
				(hide yes)
			)
		)
		(property "Datasheet" "https://www.murata.com/products/productdetail?partno=GRM155R60J106ME15%23"
			(at 151.765 34.29 0)
			(effects
				(font
					(size 1.27 1.27)
					(thickness 0.15)
				)
				(justify left bottom)
				(hide yes)
			)
		)
		(property "Description" ""
			(at 136.525 54.61 0)
			(effects
				(font
					(size 1.27 1.27)
				)
			)
		)
		(property "MPN" "GRM155R60J106ME15D"
			(at 154.305 34.29 0)
			(effects
				(font
					(size 1.27 1.27)
					(thickness 0.15)
				)
				(justify left bottom)
				(hide yes)
			)
		)
		(property "Manufacturer" "Murata"
			(at 156.845 34.29 0)
			(effects
				(font
					(size 1.27 1.27)
					(thickness 0.15)
				)
				(justify left bottom)
				(hide yes)
			)
		)
		(property "License" "Apache-2.0"
			(at 159.385 34.29 0)
			(effects
				(font
					(size 1.27 1.27)
					(thickness 0.15)
				)
				(justify left bottom)
				(hide yes)
			)
		)
		(property "Author" "Antmicro"
			(at 161.925 34.29 0)
			(effects
				(font
					(size 1.27 1.27)
					(thickness 0.15)
				)
				(justify left bottom)
				(hide yes)
			)
		)
		(property "Val" "10u"
			(at 138.8491 53.7567 90)
			(effects
				(font
					(size 1.27 1.27)
					(thickness 0.15)
				)
				(justify right)
			)
		)
		(property "Voltage" "6.3V"
			(at 164.465 34.29 0)
			(effects
				(font
					(size 1.27 1.27)
				)
				(justify left bottom)
				(hide yes)
			)
		)
		(property "Dielectric" "X5R"
			(at 167.005 34.29 0)
			(effects
				(font
					(size 1.27 1.27)
				)
				(justify left bottom)
				(hide yes)
			)
		)
		(pin "1"
		)
		(pin "2"
		)
		(instances
			(project "sodimm-ddr5-tester"
				(path ""
					(reference "C113")
					(unit 1)
				)
			)
		)
	)
	(symbol
		(lib_id "antmicroResistors0402:R_330R_0402")
		(at 90.17 246.38 0)
		(unit 1)
		(exclude_from_sim no)
		(in_bom yes)
		(on_board yes)
		(dnp no)
		(property "Reference" "R67"
			(at 95.25 246.38 0)
			(effects
				(font
					(size 1.27 1.27)
				)
				(justify left bottom)
			)
		)
		(property "Value" "R_330R_0402"
			(at 110.49 259.08 0)
			(effects
				(font
					(size 1.27 1.27)
					(thickness 0.15)
				)
				(justify left bottom)
				(hide yes)
			)
		)
		(property "Footprint" "antmicro-footprints:R_0402_1005Metric"
			(at 110.49 261.62 0)
			(effects
				(font
					(size 1.27 1.27)
					(thickness 0.15)
				)
				(justify left bottom)
				(hide yes)
			)
		)
		(property "Datasheet" "https://www.bourns.com/docs/product-datasheets/cr.pdf"
			(at 110.49 264.16 0)
			(effects
				(font
					(size 1.27 1.27)
					(thickness 0.15)
				)
				(justify left bottom)
				(hide yes)
			)
		)
		(property "Description" ""
			(at 90.17 246.38 0)
			(effects
				(font
					(size 1.27 1.27)
				)
			)
		)
		(property "Manufacturer" "Bourns"
			(at 110.49 269.24 0)
			(effects
				(font
					(size 1.27 1.27)
					(thickness 0.15)
				)
				(justify left bottom)
				(hide yes)
			)
		)
		(property "MPN" "CR0402-FX-3300GLF"
			(at 110.49 266.7 0)
			(effects
				(font
					(size 1.27 1.27)
					(thickness 0.15)
				)
				(justify left bottom)
				(hide yes)
			)
		)
		(property "Val" "330R"
			(at 85.09 246.38 0)
			(effects
				(font
					(size 1.27 1.27)
					(thickness 0.15)
				)
				(justify left bottom)
			)
		)
		(property "License" "Apache-2.0"
			(at 110.49 271.78 0)
			(effects
				(font
					(size 1.27 1.27)
					(thickness 0.15)
				)
				(justify left bottom)
				(hide yes)
			)
		)
		(property "Author" "Antmicro"
			(at 110.49 274.32 0)
			(effects
				(font
					(size 1.27 1.27)
					(thickness 0.15)
				)
				(justify left bottom)
				(hide yes)
			)
		)
		(property "Tolerance" "1%"
			(at 110.49 256.54 0)
			(effects
				(font
					(size 1.27 1.27)
				)
				(justify left bottom)
				(hide yes)
			)
		)
		(pin "1"
		)
		(pin "2"
		)
		(instances
			(project "sodimm-ddr5-tester"
				(path ""
					(reference "R67")
					(unit 1)
				)
			)
		)
	)
	(symbol
		(lib_id "antmicroResistors0402:R_47k_0402")
		(at 277.495 102.235 180)
		(unit 1)
		(exclude_from_sim no)
		(in_bom yes)
		(on_board yes)
		(dnp no)
		(property "Reference" "R51"
			(at 274.955 97.155 0)
			(effects
				(font
					(size 1.27 1.27)
				)
			)
		)
		(property "Value" "R_47k_0402"
			(at 257.175 89.535 0)
			(effects
				(font
					(size 1.27 1.27)
					(thickness 0.15)
				)
				(justify left bottom)
				(hide yes)
			)
		)
		(property "Footprint" "antmicro-footprints:R_0402_1005Metric"
			(at 257.175 86.995 0)
			(effects
				(font
					(size 1.27 1.27)
					(thickness 0.15)
				)
				(justify left bottom)
				(hide yes)
			)
		)
		(property "Datasheet" "https://www.bourns.com/docs/product-datasheets/cr.pdf"
			(at 257.175 84.455 0)
			(effects
				(font
					(size 1.27 1.27)
					(thickness 0.15)
				)
				(justify left bottom)
				(hide yes)
			)
		)
		(property "Description" ""
			(at 277.495 102.235 0)
			(effects
				(font
					(size 1.27 1.27)
				)
			)
		)
		(property "Manufacturer" "Bourns"
			(at 257.175 79.375 0)
			(effects
				(font
					(size 1.27 1.27)
					(thickness 0.15)
				)
				(justify left bottom)
				(hide yes)
			)
		)
		(property "MPN" "CR0402-FX-4702GLF"
			(at 257.175 81.915 0)
			(effects
				(font
					(size 1.27 1.27)
					(thickness 0.15)
				)
				(justify left bottom)
				(hide yes)
			)
		)
		(property "Val" "47k"
			(at 274.955 99.695 0)
			(effects
				(font
					(size 1.27 1.27)
					(thickness 0.15)
				)
			)
		)
		(property "License" "Apache-2.0"
			(at 257.175 76.835 0)
			(effects
				(font
					(size 1.27 1.27)
					(thickness 0.15)
				)
				(justify left bottom)
				(hide yes)
			)
		)
		(property "Author" "Antmicro"
			(at 257.175 74.295 0)
			(effects
				(font
					(size 1.27 1.27)
					(thickness 0.15)
				)
				(justify left bottom)
				(hide yes)
			)
		)
		(property "Tolerance" "1%"
			(at 257.175 92.075 0)
			(effects
				(font
					(size 1.27 1.27)
				)
				(justify left bottom)
				(hide yes)
			)
		)
		(pin "1"
		)
		(pin "2"
		)
		(instances
			(project "sodimm-ddr5-tester"
				(path ""
					(reference "R51")
					(unit 1)
				)
			)
		)
	)
	(symbol
		(lib_id "antmicroTestPoints:TP_1mm_SMD")
		(at 257.81 275.59 270)
		(unit 1)
		(exclude_from_sim no)
		(in_bom yes)
		(on_board yes)
		(dnp no)
		(property "Reference" "TP48"
			(at 257.81 280.5628 90)
			(effects
				(font
					(size 1.27 1.27)
				)
			)
		)
		(property "Value" "TP_1mm_SMD"
			(at 250.19 290.83 0)
			(effects
				(font
					(size 1.27 1.27)
					(thickness 0.15)
				)
				(justify left bottom)
				(hide yes)
			)
		)
		(property "Footprint" "antmicro-footprints:TP_SMD_1mm"
			(at 247.65 290.83 0)
			(effects
				(font
					(size 1.27 1.27)
					(thickness 0.15)
				)
				(justify left bottom)
				(hide yes)
			)
		)
		(property "Datasheet" ""
			(at 245.11 290.83 0)
			(effects
				(font
					(size 1.27 1.27)
					(thickness 0.15)
				)
				(justify left bottom)
				(hide yes)
			)
		)
		(property "Description" ""
			(at 257.81 275.59 0)
			(effects
				(font
					(size 1.27 1.27)
				)
			)
		)
		(property "MPN" ""
			(at 257.81 275.59 0)
			(effects
				(font
					(size 1.27 1.27)
				)
				(hide yes)
			)
		)
		(property "Manufacturer" ""
			(at 257.81 275.59 0)
			(effects
				(font
					(size 1.27 1.27)
				)
				(hide yes)
			)
		)
		(property "Author" "Antmicro"
			(at 242.57 290.83 0)
			(effects
				(font
					(size 1.27 1.27)
					(thickness 0.15)
				)
				(justify left bottom)
				(hide yes)
			)
		)
		(property "License" "Apache-2.0"
			(at 240.03 290.83 0)
			(effects
				(font
					(size 1.27 1.27)
					(thickness 0.15)
				)
				(justify left bottom)
				(hide yes)
			)
		)
		(pin "1"
		)
		(instances
			(project "sodimm-ddr5-tester"
				(path ""
					(reference "TP48")
					(unit 1)
				)
			)
		)
	)
	(symbol
		(lib_id "antmicroPMICVoltageRegulatorsLinear:NCP718BSN330T1G")
		(at 109.855 46.99 0)
		(unit 1)
		(exclude_from_sim no)
		(in_bom yes)
		(on_board yes)
		(dnp no)
		(fields_autoplaced yes)
		(property "Reference" "U5"
			(at 120.015 40.765 0)
			(effects
				(font
					(size 1.27 1.27)
					(thickness 0.15)
				)
			)
		)
		(property "Value" "NCP718BSN330T1G"
			(at 120.015 43.2887 0)
			(effects
				(font
					(size 1.27 1.27)
					(thickness 0.15)
				)
			)
		)
		(property "Footprint" "antmicro-footprints:SOT-23-5"
			(at 145.415 55.88 0)
			(effects
				(font
					(size 1.27 1.27)
					(thickness 0.15)
				)
				(justify left bottom)
				(hide yes)
			)
		)
		(property "Datasheet" "https://www.mouser.com/datasheet/2/308/NCP718_D-1224359.pdf"
			(at 145.415 58.42 0)
			(effects
				(font
					(size 1.27 1.27)
					(thickness 0.15)
				)
				(justify left bottom)
				(hide yes)
			)
		)
		(property "Description" ""
			(at 109.855 46.99 0)
			(effects
				(font
					(size 1.27 1.27)
				)
			)
		)
		(property "MPN" "NCP718BSN330T1G"
			(at 145.415 60.96 0)
			(effects
				(font
					(size 1.27 1.27)
					(thickness 0.15)
				)
				(justify left bottom)
				(hide yes)
			)
		)
		(property "Manufacturer" "ON Semiconductor"
			(at 145.415 63.5 0)
			(effects
				(font
					(size 1.27 1.27)
					(thickness 0.15)
				)
				(justify left bottom)
				(hide yes)
			)
		)
		(property "Author" "Antmicro"
			(at 145.415 66.04 0)
			(effects
				(font
					(size 1.27 1.27)
					(thickness 0.15)
				)
				(justify left bottom)
				(hide yes)
			)
		)
		(property "License" "Apache-2.0"
			(at 145.415 68.58 0)
			(effects
				(font
					(size 1.27 1.27)
					(thickness 0.15)
				)
				(justify left bottom)
				(hide yes)
			)
		)
		(pin "1"
		)
		(pin "2"
		)
		(pin "3"
		)
		(pin "4"
		)
		(pin "5"
		)
		(instances
			(project "sodimm-ddr5-tester"
				(path ""
					(reference "U5")
					(unit 1)
				)
			)
		)
	)
	(symbol
		(lib_id "antmicroCapacitors0402:C_100n_0402")
		(at 360.045 173.99 90)
		(unit 1)
		(exclude_from_sim no)
		(in_bom yes)
		(on_board yes)
		(dnp no)
		(fields_autoplaced yes)
		(property "Reference" "C235"
			(at 362.3691 170.613 90)
			(effects
				(font
					(size 1.27 1.27)
					(thickness 0.15)
				)
				(justify right)
			)
		)
		(property "Value" "C_100n_0402"
			(at 370.205 153.67 0)
			(effects
				(font
					(size 1.27 1.27)
					(thickness 0.15)
				)
				(justify left bottom)
				(hide yes)
			)
		)
		(property "Footprint" "antmicro-footprints:C_0402_1005Metric"
			(at 372.745 153.67 0)
			(effects
				(font
					(size 1.27 1.27)
					(thickness 0.15)
				)
				(justify left bottom)
				(hide yes)
			)
		)
		(property "Datasheet" "https://www.murata.com/products/productdetail?partno=GRM155R61H104KE14%23"
			(at 375.285 153.67 0)
			(effects
				(font
					(size 1.27 1.27)
					(thickness 0.15)
				)
				(justify left bottom)
				(hide yes)
			)
		)
		(property "Description" ""
			(at 360.045 173.99 0)
			(effects
				(font
					(size 1.27 1.27)
				)
			)
		)
		(property "MPN" "GRM155R61H104KE14D"
			(at 377.825 153.67 0)
			(effects
				(font
					(size 1.27 1.27)
					(thickness 0.15)
				)
				(justify left bottom)
				(hide yes)
			)
		)
		(property "Manufacturer" "Murata"
			(at 380.365 153.67 0)
			(effects
				(font
					(size 1.27 1.27)
					(thickness 0.15)
				)
				(justify left bottom)
				(hide yes)
			)
		)
		(property "License" "Apache-2.0"
			(at 382.905 153.67 0)
			(effects
				(font
					(size 1.27 1.27)
					(thickness 0.15)
				)
				(justify left bottom)
				(hide yes)
			)
		)
		(property "Author" "Antmicro"
			(at 385.445 153.67 0)
			(effects
				(font
					(size 1.27 1.27)
					(thickness 0.15)
				)
				(justify left bottom)
				(hide yes)
			)
		)
		(property "Val" "100n"
			(at 362.3691 173.1367 90)
			(effects
				(font
					(size 1.27 1.27)
					(thickness 0.15)
				)
				(justify right)
			)
		)
		(property "Voltage" "50V"
			(at 387.985 153.67 0)
			(effects
				(font
					(size 1.27 1.27)
				)
				(justify left bottom)
				(hide yes)
			)
		)
		(property "Dielectric" "X5R"
			(at 390.525 153.67 0)
			(effects
				(font
					(size 1.27 1.27)
				)
				(justify left bottom)
				(hide yes)
			)
		)
		(pin "1"
		)
		(pin "2"
		)
		(instances
			(project "sodimm-ddr5-tester"
				(path ""
					(reference "C235")
					(unit 1)
				)
			)
		)
	)
	(symbol
		(lib_id "antmicroResistors0402:R_22R_0402")
		(at 179.705 151.13 0)
		(unit 1)
		(exclude_from_sim no)
		(in_bom no)
		(on_board yes)
		(dnp yes)
		(property "Reference" "R60"
			(at 186.69 149.86 0)
			(effects
				(font
					(size 1.27 1.27)
				)
			)
		)
		(property "Value" "R_22R_0402"
			(at 200.025 163.83 0)
			(effects
				(font
					(size 1.27 1.27)
					(thickness 0.15)
				)
				(justify left bottom)
				(hide yes)
			)
		)
		(property "Footprint" "antmicro-footprints:R_0402_1005Metric"
			(at 200.025 166.37 0)
			(effects
				(font
					(size 1.27 1.27)
					(thickness 0.15)
				)
				(justify left bottom)
				(hide yes)
			)
		)
		(property "Datasheet" "https://www.bourns.com/docs/product-datasheets/cr.pdf"
			(at 200.025 168.91 0)
			(effects
				(font
					(size 1.27 1.27)
					(thickness 0.15)
				)
				(justify left bottom)
				(hide yes)
			)
		)
		(property "Description" ""
			(at 179.705 151.13 0)
			(effects
				(font
					(size 1.27 1.27)
				)
			)
		)
		(property "Manufacturer" "Bourns"
			(at 200.025 173.99 0)
			(effects
				(font
					(size 1.27 1.27)
					(thickness 0.15)
				)
				(justify left bottom)
				(hide yes)
			)
		)
		(property "MPN" "CR0402-FX-22R0GLF"
			(at 200.025 171.45 0)
			(effects
				(font
					(size 1.27 1.27)
					(thickness 0.15)
				)
				(justify left bottom)
				(hide yes)
			)
		)
		(property "Val" "22R"
			(at 177.8 149.86 0)
			(effects
				(font
					(size 1.27 1.27)
					(thickness 0.15)
				)
			)
		)
		(property "License" "Apache-2.0"
			(at 200.025 176.53 0)
			(effects
				(font
					(size 1.27 1.27)
					(thickness 0.15)
				)
				(justify left bottom)
				(hide yes)
			)
		)
		(property "Author" "Antmicro"
			(at 200.025 179.07 0)
			(effects
				(font
					(size 1.27 1.27)
					(thickness 0.15)
				)
				(justify left bottom)
				(hide yes)
			)
		)
		(property "Tolerance" "1%"
			(at 200.025 161.29 0)
			(effects
				(font
					(size 1.27 1.27)
				)
				(justify left bottom)
				(hide yes)
			)
		)
		(pin "1"
		)
		(pin "2"
		)
		(instances
			(project "sodimm-ddr5-tester"
				(path ""
					(reference "R60")
					(unit 1)
				)
			)
		)
	)
	(symbol
		(lib_id "antmicroTVSDiodes:TPD4E05U06QDQARQ1")
		(at 121.285 81.915 0)
		(mirror y)
		(unit 1)
		(exclude_from_sim no)
		(in_bom yes)
		(on_board yes)
		(dnp no)
		(property "Reference" "U8"
			(at 114.935 76.2 0)
			(effects
				(font
					(size 1.27 1.27)
				)
				(justify left)
			)
		)
		(property "Value" "TPD4E05U06QDQARQ1"
			(at 133.35 78.105 0)
			(effects
				(font
					(size 1.27 1.27)
					(thickness 0.15)
				)
				(justify left)
			)
		)
		(property "Footprint" "antmicro-footprints:USON-10_2.5x1mm_P0.5mm"
			(at 97.155 86.995 0)
			(effects
				(font
					(size 1.27 1.27)
					(thickness 0.15)
				)
				(justify left bottom)
				(hide yes)
			)
		)
		(property "Datasheet" "https://www.ti.com/lit/ds/symlink/tpd4e05u06-q1.pdf?HQS=dis-mous-null-mousermode-dsf-pf-null-wwe&ts=1663591265741&ref_url=https%253A%252F%252Fwww.mouser.com%252F"
			(at 97.155 89.535 0)
			(effects
				(font
					(size 1.27 1.27)
					(thickness 0.15)
				)
				(justify left bottom)
				(hide yes)
			)
		)
		(property "Description" ""
			(at 121.285 81.915 0)
			(effects
				(font
					(size 1.27 1.27)
				)
			)
		)
		(property "Manufacturer" "Texas Instruments"
			(at 97.155 92.075 0)
			(effects
				(font
					(size 1.27 1.27)
					(thickness 0.15)
				)
				(justify left bottom)
				(hide yes)
			)
		)
		(property "MPN" "TPD4E05U06QDQARQ1"
			(at 97.155 94.615 0)
			(effects
				(font
					(size 1.27 1.27)
					(thickness 0.15)
				)
				(justify left bottom)
				(hide yes)
			)
		)
		(property "Author" "Antmicro"
			(at 97.155 97.155 0)
			(effects
				(font
					(size 1.27 1.27)
					(thickness 0.15)
				)
				(justify left bottom)
				(hide yes)
			)
		)
		(property "License" "Apache-2.0"
			(at 97.155 99.695 0)
			(effects
				(font
					(size 1.27 1.27)
					(thickness 0.15)
				)
				(justify left bottom)
				(hide yes)
			)
		)
		(pin "1"
		)
		(pin "10"
		)
		(pin "2"
		)
		(pin "3"
		)
		(pin "4"
		)
		(pin "5"
		)
		(pin "6"
		)
		(pin "7"
		)
		(pin "8"
		)
		(pin "9"
		)
		(instances
			(project "sodimm-ddr5-tester"
				(path ""
					(reference "U8")
					(unit 1)
				)
			)
		)
	)
	(symbol
		(lib_id "antmicropower:GND")
		(at 372.11 194.945 0)
		(unit 1)
		(exclude_from_sim no)
		(in_bom yes)
		(on_board yes)
		(dnp no)
		(property "Reference" "#PWR017"
			(at 372.11 201.295 0)
			(effects
				(font
					(size 1.27 1.27)
				)
				(hide yes)
			)
		)
		(property "Value" "GND"
			(at 370.205 199.39 0)
			(effects
				(font
					(size 1.27 1.27)
					(thickness 0.15)
				)
				(justify left bottom)
			)
		)
		(property "Footprint" ""
			(at 381 202.565 0)
			(effects
				(font
					(size 1.27 1.27)
					(thickness 0.15)
				)
				(justify left bottom)
				(hide yes)
			)
		)
		(property "Datasheet" ""
			(at 381 207.645 0)
			(effects
				(font
					(size 1.27 1.27)
					(thickness 0.15)
				)
				(justify left bottom)
				(hide yes)
			)
		)
		(property "Description" ""
			(at 381 210.185 0)
			(effects
				(font
					(size 1.27 1.27)
				)
				(justify left bottom)
				(hide yes)
			)
		)
		(property "Author" "Antmicro"
			(at 381 202.565 0)
			(effects
				(font
					(size 1.27 1.27)
					(thickness 0.15)
				)
				(justify left bottom)
				(hide yes)
			)
		)
		(property "License" "Apache-2.0"
			(at 381 205.105 0)
			(effects
				(font
					(size 1.27 1.27)
					(thickness 0.15)
				)
				(justify left bottom)
				(hide yes)
			)
		)
		(pin "1"
		)
		(instances
			(project "sodimm-ddr5-tester"
				(path ""
					(reference "#PWR017")
					(unit 1)
				)
			)
		)
	)
	(symbol
		(lib_id "antmicroResistors0402:R_330R_0402")
		(at 80.645 87.63 0)
		(mirror y)
		(unit 1)
		(exclude_from_sim no)
		(in_bom yes)
		(on_board yes)
		(dnp no)
		(property "Reference" "R90"
			(at 78.105 82.55 0)
			(effects
				(font
					(size 1.27 1.27)
				)
			)
		)
		(property "Value" "R_330R_0402"
			(at 60.325 100.33 0)
			(effects
				(font
					(size 1.27 1.27)
					(thickness 0.15)
				)
				(justify left bottom)
				(hide yes)
			)
		)
		(property "Footprint" "antmicro-footprints:R_0402_1005Metric"
			(at 60.325 102.87 0)
			(effects
				(font
					(size 1.27 1.27)
					(thickness 0.15)
				)
				(justify left bottom)
				(hide yes)
			)
		)
		(property "Datasheet" "https://www.bourns.com/docs/product-datasheets/cr.pdf"
			(at 60.325 105.41 0)
			(effects
				(font
					(size 1.27 1.27)
					(thickness 0.15)
				)
				(justify left bottom)
				(hide yes)
			)
		)
		(property "Description" ""
			(at 80.645 87.63 0)
			(effects
				(font
					(size 1.27 1.27)
				)
			)
		)
		(property "Manufacturer" "Bourns"
			(at 60.325 110.49 0)
			(effects
				(font
					(size 1.27 1.27)
					(thickness 0.15)
				)
				(justify left bottom)
				(hide yes)
			)
		)
		(property "MPN" "CR0402-FX-3300GLF"
			(at 60.325 107.95 0)
			(effects
				(font
					(size 1.27 1.27)
					(thickness 0.15)
				)
				(justify left bottom)
				(hide yes)
			)
		)
		(property "Val" "330R"
			(at 78.105 85.09 0)
			(effects
				(font
					(size 1.27 1.27)
					(thickness 0.15)
				)
			)
		)
		(property "License" "Apache-2.0"
			(at 60.325 113.03 0)
			(effects
				(font
					(size 1.27 1.27)
					(thickness 0.15)
				)
				(justify left bottom)
				(hide yes)
			)
		)
		(property "Author" "Antmicro"
			(at 60.325 115.57 0)
			(effects
				(font
					(size 1.27 1.27)
					(thickness 0.15)
				)
				(justify left bottom)
				(hide yes)
			)
		)
		(property "Tolerance" "1%"
			(at 60.325 97.79 0)
			(effects
				(font
					(size 1.27 1.27)
				)
				(justify left bottom)
				(hide yes)
			)
		)
		(pin "1"
		)
		(pin "2"
		)
		(instances
			(project "sodimm-ddr5-tester"
				(path ""
					(reference "R90")
					(unit 1)
				)
			)
		)
	)
	(symbol
		(lib_id "antmicropower:+3V3_AON")
		(at 265.43 128.905 0)
		(mirror y)
		(unit 1)
		(exclude_from_sim no)
		(in_bom yes)
		(on_board yes)
		(dnp no)
		(property "Reference" "#PWR0193"
			(at 265.43 132.715 0)
			(effects
				(font
					(size 1.27 1.27)
				)
				(hide yes)
			)
		)
		(property "Value" "+3V3_AON"
			(at 271.145 125.73 0)
			(effects
				(font
					(size 1.27 1.27)
				)
			)
		)
		(property "Footprint" ""
			(at 265.43 128.905 0)
			(effects
				(font
					(size 1.27 1.27)
				)
				(hide yes)
			)
		)
		(property "Datasheet" ""
			(at 265.43 128.905 0)
			(effects
				(font
					(size 1.27 1.27)
				)
				(hide yes)
			)
		)
		(property "Description" ""
			(at 265.43 128.905 0)
			(effects
				(font
					(size 1.27 1.27)
				)
			)
		)
		(pin "1"
		)
		(instances
			(project "sodimm-ddr5-tester"
				(path ""
					(reference "#PWR0193")
					(unit 1)
				)
			)
		)
	)
	(symbol
		(lib_id "antmicropower:+3V3_AON")
		(at 307.34 127.635 0)
		(mirror y)
		(unit 1)
		(exclude_from_sim no)
		(in_bom yes)
		(on_board yes)
		(dnp no)
		(property "Reference" "#PWR0191"
			(at 307.34 131.445 0)
			(effects
				(font
					(size 1.27 1.27)
				)
				(hide yes)
			)
		)
		(property "Value" "+3V3_AON"
			(at 313.055 124.46 0)
			(effects
				(font
					(size 1.27 1.27)
				)
			)
		)
		(property "Footprint" ""
			(at 307.34 127.635 0)
			(effects
				(font
					(size 1.27 1.27)
				)
				(hide yes)
			)
		)
		(property "Datasheet" ""
			(at 307.34 127.635 0)
			(effects
				(font
					(size 1.27 1.27)
				)
				(hide yes)
			)
		)
		(property "Description" ""
			(at 307.34 127.635 0)
			(effects
				(font
					(size 1.27 1.27)
				)
			)
		)
		(pin "1"
		)
		(instances
			(project "sodimm-ddr5-tester"
				(path ""
					(reference "#PWR0191")
					(unit 1)
				)
			)
		)
	)
	(symbol
		(lib_id "antmicroTestPoints:TP_1mm_SMD")
		(at 276.86 275.59 270)
		(unit 1)
		(exclude_from_sim no)
		(in_bom yes)
		(on_board yes)
		(dnp no)
		(property "Reference" "TP51"
			(at 276.86 280.5628 90)
			(effects
				(font
					(size 1.27 1.27)
				)
			)
		)
		(property "Value" "TP_1mm_SMD"
			(at 269.24 290.83 0)
			(effects
				(font
					(size 1.27 1.27)
					(thickness 0.15)
				)
				(justify left bottom)
				(hide yes)
			)
		)
		(property "Footprint" "antmicro-footprints:TP_SMD_1mm"
			(at 266.7 290.83 0)
			(effects
				(font
					(size 1.27 1.27)
					(thickness 0.15)
				)
				(justify left bottom)
				(hide yes)
			)
		)
		(property "Datasheet" ""
			(at 264.16 290.83 0)
			(effects
				(font
					(size 1.27 1.27)
					(thickness 0.15)
				)
				(justify left bottom)
				(hide yes)
			)
		)
		(property "Description" ""
			(at 276.86 275.59 0)
			(effects
				(font
					(size 1.27 1.27)
				)
			)
		)
		(property "MPN" ""
			(at 276.86 275.59 0)
			(effects
				(font
					(size 1.27 1.27)
				)
				(hide yes)
			)
		)
		(property "Manufacturer" ""
			(at 276.86 275.59 0)
			(effects
				(font
					(size 1.27 1.27)
				)
				(hide yes)
			)
		)
		(property "Author" "Antmicro"
			(at 261.62 290.83 0)
			(effects
				(font
					(size 1.27 1.27)
					(thickness 0.15)
				)
				(justify left bottom)
				(hide yes)
			)
		)
		(property "License" "Apache-2.0"
			(at 259.08 290.83 0)
			(effects
				(font
					(size 1.27 1.27)
					(thickness 0.15)
				)
				(justify left bottom)
				(hide yes)
			)
		)
		(pin "1"
		)
		(instances
			(project "sodimm-ddr5-tester"
				(path ""
					(reference "TP51")
					(unit 1)
				)
			)
		)
	)
	(symbol
		(lib_id "antmicroLogicTranslatorsLevelShifters:TXU0304BQAR")
		(at 245.11 133.35 0)
		(unit 1)
		(exclude_from_sim no)
		(in_bom yes)
		(on_board yes)
		(dnp no)
		(property "Reference" "U13"
			(at 254 127 0)
			(effects
				(font
					(size 1.27 1.27)
				)
			)
		)
		(property "Value" "TXU0304BQAR"
			(at 254 129.54 0)
			(effects
				(font
					(size 1.27 1.27)
					(thickness 0.15)
				)
			)
		)
		(property "Footprint" "antmicro-footprints:DHVQFN-14-1EP_2.5x3mm"
			(at 276.86 138.43 0)
			(effects
				(font
					(size 1.27 1.27)
					(thickness 0.15)
				)
				(justify left bottom)
				(hide yes)
			)
		)
		(property "Datasheet" "https://www.ti.com/lit/ds/symlink/txu0304.pdf?ts=1637748643258&ref_url=https%253A%252F%252Fwww.ti.com%252Fproduct%252FTXU0304"
			(at 276.86 140.97 0)
			(effects
				(font
					(size 1.27 1.27)
					(thickness 0.15)
				)
				(justify left bottom)
				(hide yes)
			)
		)
		(property "Description" ""
			(at 245.11 133.35 0)
			(effects
				(font
					(size 1.27 1.27)
				)
			)
		)
		(property "MPN" "TXU0304BQAR"
			(at 276.86 143.51 0)
			(effects
				(font
					(size 1.27 1.27)
					(thickness 0.15)
				)
				(justify left bottom)
				(hide yes)
			)
		)
		(property "Manufacturer" "Texas Instruments"
			(at 276.86 146.05 0)
			(effects
				(font
					(size 1.27 1.27)
					(thickness 0.15)
				)
				(justify left bottom)
				(hide yes)
			)
		)
		(property "Author" "Antmicro"
			(at 276.86 148.59 0)
			(effects
				(font
					(size 1.27 1.27)
					(thickness 0.15)
				)
				(justify left bottom)
				(hide yes)
			)
		)
		(property "License" "Apache-2.0"
			(at 276.86 151.13 0)
			(effects
				(font
					(size 1.27 1.27)
					(thickness 0.15)
				)
				(justify left bottom)
				(hide yes)
			)
		)
		(pin "1"
		)
		(pin "10"
		)
		(pin "11"
		)
		(pin "12"
		)
		(pin "13"
		)
		(pin "14"
		)
		(pin "15"
		)
		(pin "2"
		)
		(pin "3"
		)
		(pin "4"
		)
		(pin "5"
		)
		(pin "6"
		)
		(pin "7"
		)
		(pin "8"
		)
		(pin "9"
		)
		(instances
			(project "sodimm-ddr5-tester"
				(path ""
					(reference "U13")
					(unit 1)
				)
			)
		)
	)
	(symbol
		(lib_id "antmicropower:GND")
		(at 243.84 118.745 0)
		(unit 1)
		(exclude_from_sim no)
		(in_bom yes)
		(on_board yes)
		(dnp no)
		(property "Reference" "#PWR0204"
			(at 243.84 125.095 0)
			(effects
				(font
					(size 1.27 1.27)
				)
				(hide yes)
			)
		)
		(property "Value" "GND"
			(at 241.935 123.19 0)
			(effects
				(font
					(size 1.27 1.27)
					(thickness 0.15)
				)
				(justify left bottom)
			)
		)
		(property "Footprint" ""
			(at 252.73 126.365 0)
			(effects
				(font
					(size 1.27 1.27)
					(thickness 0.15)
				)
				(justify left bottom)
				(hide yes)
			)
		)
		(property "Datasheet" ""
			(at 252.73 131.445 0)
			(effects
				(font
					(size 1.27 1.27)
					(thickness 0.15)
				)
				(justify left bottom)
				(hide yes)
			)
		)
		(property "Description" ""
			(at 252.73 133.985 0)
			(effects
				(font
					(size 1.27 1.27)
				)
				(justify left bottom)
				(hide yes)
			)
		)
		(property "Author" "Antmicro"
			(at 252.73 126.365 0)
			(effects
				(font
					(size 1.27 1.27)
					(thickness 0.15)
				)
				(justify left bottom)
				(hide yes)
			)
		)
		(property "License" "Apache-2.0"
			(at 252.73 128.905 0)
			(effects
				(font
					(size 1.27 1.27)
					(thickness 0.15)
				)
				(justify left bottom)
				(hide yes)
			)
		)
		(pin "1"
		)
		(instances
			(project "sodimm-ddr5-tester"
				(path ""
					(reference "#PWR0204")
					(unit 1)
				)
			)
		)
	)
	(symbol
		(lib_id "antmicroResistors0402:R_22R_0402")
		(at 179.705 143.51 0)
		(unit 1)
		(exclude_from_sim no)
		(in_bom no)
		(on_board yes)
		(dnp yes)
		(property "Reference" "R58"
			(at 186.69 142.24 0)
			(effects
				(font
					(size 1.27 1.27)
				)
			)
		)
		(property "Value" "R_22R_0402"
			(at 200.025 156.21 0)
			(effects
				(font
					(size 1.27 1.27)
					(thickness 0.15)
				)
				(justify left bottom)
				(hide yes)
			)
		)
		(property "Footprint" "antmicro-footprints:R_0402_1005Metric"
			(at 200.025 158.75 0)
			(effects
				(font
					(size 1.27 1.27)
					(thickness 0.15)
				)
				(justify left bottom)
				(hide yes)
			)
		)
		(property "Datasheet" "https://www.bourns.com/docs/product-datasheets/cr.pdf"
			(at 200.025 161.29 0)
			(effects
				(font
					(size 1.27 1.27)
					(thickness 0.15)
				)
				(justify left bottom)
				(hide yes)
			)
		)
		(property "Description" ""
			(at 179.705 143.51 0)
			(effects
				(font
					(size 1.27 1.27)
				)
			)
		)
		(property "Manufacturer" "Bourns"
			(at 200.025 166.37 0)
			(effects
				(font
					(size 1.27 1.27)
					(thickness 0.15)
				)
				(justify left bottom)
				(hide yes)
			)
		)
		(property "MPN" "CR0402-FX-22R0GLF"
			(at 200.025 163.83 0)
			(effects
				(font
					(size 1.27 1.27)
					(thickness 0.15)
				)
				(justify left bottom)
				(hide yes)
			)
		)
		(property "Val" "22R"
			(at 177.8 142.24 0)
			(effects
				(font
					(size 1.27 1.27)
					(thickness 0.15)
				)
			)
		)
		(property "License" "Apache-2.0"
			(at 200.025 168.91 0)
			(effects
				(font
					(size 1.27 1.27)
					(thickness 0.15)
				)
				(justify left bottom)
				(hide yes)
			)
		)
		(property "Author" "Antmicro"
			(at 200.025 171.45 0)
			(effects
				(font
					(size 1.27 1.27)
					(thickness 0.15)
				)
				(justify left bottom)
				(hide yes)
			)
		)
		(property "Tolerance" "1%"
			(at 200.025 153.67 0)
			(effects
				(font
					(size 1.27 1.27)
				)
				(justify left bottom)
				(hide yes)
			)
		)
		(pin "1"
		)
		(pin "2"
		)
		(instances
			(project "sodimm-ddr5-tester"
				(path ""
					(reference "R58")
					(unit 1)
				)
			)
		)
	)
	(symbol
		(lib_id "antmicroResistors0402:R_0R_0402")
		(at 295.91 144.78 180)
		(unit 1)
		(exclude_from_sim no)
		(in_bom yes)
		(on_board yes)
		(dnp no)
		(property "Reference" "R93"
			(at 298.45 143.51 0)
			(effects
				(font
					(size 1.27 1.27)
				)
			)
		)
		(property "Value" "R_0R_0402"
			(at 275.59 132.08 0)
			(effects
				(font
					(size 1.27 1.27)
					(thickness 0.15)
				)
				(justify left bottom)
				(hide yes)
			)
		)
		(property "Footprint" "antmicro-footprints:R_0402_1005Metric"
			(at 275.59 129.54 0)
			(effects
				(font
					(size 1.27 1.27)
					(thickness 0.15)
				)
				(justify left bottom)
				(hide yes)
			)
		)
		(property "Datasheet" "https://industrial.panasonic.com/cdbs/www-data/pdf/RDA0000/AOA0000C301.pdf"
			(at 275.59 127 0)
			(effects
				(font
					(size 1.27 1.27)
					(thickness 0.15)
				)
				(justify left bottom)
				(hide yes)
			)
		)
		(property "Description" ""
			(at 295.91 144.78 0)
			(effects
				(font
					(size 1.27 1.27)
				)
			)
		)
		(property "Manufacturer" "Panasonic"
			(at 275.59 121.92 0)
			(effects
				(font
					(size 1.27 1.27)
					(thickness 0.15)
				)
				(justify left bottom)
				(hide yes)
			)
		)
		(property "MPN" "ERJ2GE0R00X"
			(at 275.59 124.46 0)
			(effects
				(font
					(size 1.27 1.27)
					(thickness 0.15)
				)
				(justify left bottom)
				(hide yes)
			)
		)
		(property "Val" "0R"
			(at 289.56 143.51 0)
			(effects
				(font
					(size 1.27 1.27)
					(thickness 0.15)
				)
			)
		)
		(property "License" "Apache-2.0"
			(at 275.59 119.38 0)
			(effects
				(font
					(size 1.27 1.27)
					(thickness 0.15)
				)
				(justify left bottom)
				(hide yes)
			)
		)
		(property "Author" "Antmicro"
			(at 275.59 116.84 0)
			(effects
				(font
					(size 1.27 1.27)
					(thickness 0.15)
				)
				(justify left bottom)
				(hide yes)
			)
		)
		(property "Tolerance" "~"
			(at 275.59 134.62 0)
			(effects
				(font
					(size 1.27 1.27)
				)
				(justify left bottom)
				(hide yes)
			)
		)
		(property "Current" "1A"
			(at 293.37 140.97 0)
			(effects
				(font
					(size 1.27 1.27)
					(thickness 0.15)
				)
				(hide yes)
			)
		)
		(pin "1"
		)
		(pin "2"
		)
		(instances
			(project "sodimm-ddr5-tester"
				(path ""
					(reference "R93")
					(unit 1)
				)
			)
		)
	)
	(symbol
		(lib_id "antmicroCapacitors0402:C_100n_0402")
		(at 75.565 96.52 0)
		(mirror x)
		(unit 1)
		(exclude_from_sim no)
		(in_bom yes)
		(on_board yes)
		(dnp no)
		(property "Reference" "C133"
			(at 78.0986 90.805 0)
			(effects
				(font
					(size 1.27 1.27)
				)
			)
		)
		(property "Value" "C_100n_0402"
			(at 95.885 86.36 0)
			(effects
				(font
					(size 1.27 1.27)
					(thickness 0.15)
				)
				(justify left bottom)
				(hide yes)
			)
		)
		(property "Footprint" "antmicro-footprints:C_0402_1005Metric"
			(at 95.885 83.82 0)
			(effects
				(font
					(size 1.27 1.27)
					(thickness 0.15)
				)
				(justify left bottom)
				(hide yes)
			)
		)
		(property "Datasheet" "https://www.murata.com/products/productdetail?partno=GRM155R61H104KE14%23"
			(at 95.885 81.28 0)
			(effects
				(font
					(size 1.27 1.27)
					(thickness 0.15)
				)
				(justify left bottom)
				(hide yes)
			)
		)
		(property "Description" ""
			(at 75.565 96.52 0)
			(effects
				(font
					(size 1.27 1.27)
				)
			)
		)
		(property "Manufacturer" "Murata"
			(at 95.885 76.2 0)
			(effects
				(font
					(size 1.27 1.27)
					(thickness 0.15)
				)
				(justify left bottom)
				(hide yes)
			)
		)
		(property "MPN" "GRM155R61H104KE14D"
			(at 95.885 78.74 0)
			(effects
				(font
					(size 1.27 1.27)
					(thickness 0.15)
				)
				(justify left bottom)
				(hide yes)
			)
		)
		(property "Val" "100n"
			(at 78.105 93.345 0)
			(effects
				(font
					(size 1.27 1.27)
					(thickness 0.15)
				)
			)
		)
		(property "License" "Apache-2.0"
			(at 95.885 73.66 0)
			(effects
				(font
					(size 1.27 1.27)
					(thickness 0.15)
				)
				(justify left bottom)
				(hide yes)
			)
		)
		(property "Author" "Antmicro"
			(at 95.885 71.12 0)
			(effects
				(font
					(size 1.27 1.27)
					(thickness 0.15)
				)
				(justify left bottom)
				(hide yes)
			)
		)
		(property "Voltage" "50V"
			(at 95.885 68.58 0)
			(effects
				(font
					(size 1.27 1.27)
				)
				(justify left bottom)
				(hide yes)
			)
		)
		(property "Dielectric" "X5R"
			(at 95.885 66.04 0)
			(effects
				(font
					(size 1.27 1.27)
				)
				(justify left bottom)
				(hide yes)
			)
		)
		(pin "1"
		)
		(pin "2"
		)
		(instances
			(project "sodimm-ddr5-tester"
				(path ""
					(reference "C133")
					(unit 1)
				)
			)
		)
	)
	(symbol
		(lib_id "antmicroTestPoints:TP_1mm_SMD")
		(at 238.76 275.59 270)
		(unit 1)
		(exclude_from_sim no)
		(in_bom yes)
		(on_board yes)
		(dnp no)
		(property "Reference" "TP45"
			(at 238.76 280.5628 90)
			(effects
				(font
					(size 1.27 1.27)
				)
			)
		)
		(property "Value" "TP_1mm_SMD"
			(at 231.14 290.83 0)
			(effects
				(font
					(size 1.27 1.27)
					(thickness 0.15)
				)
				(justify left bottom)
				(hide yes)
			)
		)
		(property "Footprint" "antmicro-footprints:TP_SMD_1mm"
			(at 228.6 290.83 0)
			(effects
				(font
					(size 1.27 1.27)
					(thickness 0.15)
				)
				(justify left bottom)
				(hide yes)
			)
		)
		(property "Datasheet" ""
			(at 226.06 290.83 0)
			(effects
				(font
					(size 1.27 1.27)
					(thickness 0.15)
				)
				(justify left bottom)
				(hide yes)
			)
		)
		(property "Description" ""
			(at 238.76 275.59 0)
			(effects
				(font
					(size 1.27 1.27)
				)
			)
		)
		(property "MPN" ""
			(at 238.76 275.59 0)
			(effects
				(font
					(size 1.27 1.27)
				)
				(hide yes)
			)
		)
		(property "Manufacturer" ""
			(at 238.76 275.59 0)
			(effects
				(font
					(size 1.27 1.27)
				)
				(hide yes)
			)
		)
		(property "Author" "Antmicro"
			(at 223.52 290.83 0)
			(effects
				(font
					(size 1.27 1.27)
					(thickness 0.15)
				)
				(justify left bottom)
				(hide yes)
			)
		)
		(property "License" "Apache-2.0"
			(at 220.98 290.83 0)
			(effects
				(font
					(size 1.27 1.27)
					(thickness 0.15)
				)
				(justify left bottom)
				(hide yes)
			)
		)
		(pin "1"
		)
		(instances
			(project "sodimm-ddr5-tester"
				(path ""
					(reference "TP45")
					(unit 1)
				)
			)
		)
	)
	(symbol
		(lib_id "antmicropower:GND")
		(at 83.82 97.79 0)
		(mirror y)
		(unit 1)
		(exclude_from_sim no)
		(in_bom yes)
		(on_board yes)
		(dnp no)
		(fields_autoplaced yes)
		(property "Reference" "#PWR0225"
			(at 83.82 104.14 0)
			(effects
				(font
					(size 1.27 1.27)
				)
				(hide yes)
			)
		)
		(property "Value" "GND"
			(at 86.36 99.06 0)
			(effects
				(font
					(size 1.27 1.27)
					(thickness 0.15)
				)
				(justify right)
			)
		)
		(property "Footprint" ""
			(at 74.93 105.41 0)
			(effects
				(font
					(size 1.27 1.27)
					(thickness 0.15)
				)
				(justify left bottom)
				(hide yes)
			)
		)
		(property "Datasheet" ""
			(at 74.93 110.49 0)
			(effects
				(font
					(size 1.27 1.27)
					(thickness 0.15)
				)
				(justify left bottom)
				(hide yes)
			)
		)
		(property "Description" ""
			(at 74.93 113.03 0)
			(effects
				(font
					(size 1.27 1.27)
				)
				(justify left bottom)
				(hide yes)
			)
		)
		(property "Author" "Antmicro"
			(at 74.93 105.41 0)
			(effects
				(font
					(size 1.27 1.27)
					(thickness 0.15)
				)
				(justify left bottom)
				(hide yes)
			)
		)
		(property "License" "Apache-2.0"
			(at 74.93 107.95 0)
			(effects
				(font
					(size 1.27 1.27)
					(thickness 0.15)
				)
				(justify left bottom)
				(hide yes)
			)
		)
		(pin "1"
		)
		(instances
			(project "sodimm-ddr5-tester"
				(path ""
					(reference "#PWR0225")
					(unit 1)
				)
			)
		)
	)
	(symbol
		(lib_id "antmicropower:GND")
		(at 131.445 57.15 0)
		(mirror y)
		(unit 1)
		(exclude_from_sim no)
		(in_bom yes)
		(on_board yes)
		(dnp no)
		(property "Reference" "#PWR0213"
			(at 131.445 63.5 0)
			(effects
				(font
					(size 1.27 1.27)
				)
				(hide yes)
			)
		)
		(property "Value" "GND"
			(at 133.35 61.595 0)
			(effects
				(font
					(size 1.27 1.27)
					(thickness 0.15)
				)
				(justify left bottom)
			)
		)
		(property "Footprint" ""
			(at 122.555 64.77 0)
			(effects
				(font
					(size 1.27 1.27)
					(thickness 0.15)
				)
				(justify left bottom)
				(hide yes)
			)
		)
		(property "Datasheet" ""
			(at 122.555 69.85 0)
			(effects
				(font
					(size 1.27 1.27)
					(thickness 0.15)
				)
				(justify left bottom)
				(hide yes)
			)
		)
		(property "Description" ""
			(at 122.555 72.39 0)
			(effects
				(font
					(size 1.27 1.27)
				)
				(justify left bottom)
				(hide yes)
			)
		)
		(property "Author" "Antmicro"
			(at 122.555 64.77 0)
			(effects
				(font
					(size 1.27 1.27)
					(thickness 0.15)
				)
				(justify left bottom)
				(hide yes)
			)
		)
		(property "License" "Apache-2.0"
			(at 122.555 67.31 0)
			(effects
				(font
					(size 1.27 1.27)
					(thickness 0.15)
				)
				(justify left bottom)
				(hide yes)
			)
		)
		(pin "1"
		)
		(instances
			(project "sodimm-ddr5-tester"
				(path ""
					(reference "#PWR0213")
					(unit 1)
				)
			)
		)
	)
	(symbol
		(lib_id "antmicroUSBConnectors:USB-C_GCT_USB4105-GF-A")
		(at 67.31 46.99 0)
		(unit 1)
		(exclude_from_sim no)
		(in_bom yes)
		(on_board yes)
		(dnp no)
		(fields_autoplaced yes)
		(property "Reference" "J3"
			(at 53.975 40.765 0)
			(effects
				(font
					(size 1.27 1.27)
					(thickness 0.15)
				)
			)
		)
		(property "Value" "USB-C_GCT_USB4105-GF-A"
			(at 53.975 43.2887 0)
			(effects
				(font
					(size 1.27 1.27)
					(thickness 0.15)
				)
			)
		)
		(property "Footprint" "antmicro-footprints:USB-C_Receptacle_GCT_USB4105-GF-A"
			(at 105.41 54.61 0)
			(effects
				(font
					(size 1.27 1.27)
					(thickness 0.15)
				)
				(justify left bottom)
				(hide yes)
			)
		)
		(property "Datasheet" "https://gct.co/files/drawings/usb4105.pdf"
			(at 105.41 57.15 0)
			(effects
				(font
					(size 1.27 1.27)
					(thickness 0.15)
				)
				(justify left bottom)
				(hide yes)
			)
		)
		(property "Description" ""
			(at 67.31 46.99 0)
			(effects
				(font
					(size 1.27 1.27)
				)
			)
		)
		(property "Manufacturer" "GCT"
			(at 105.41 59.69 0)
			(effects
				(font
					(size 1.27 1.27)
					(thickness 0.15)
				)
				(justify left bottom)
				(hide yes)
			)
		)
		(property "MPN" "USB4105-GF-A"
			(at 105.41 62.23 0)
			(effects
				(font
					(size 1.27 1.27)
					(thickness 0.15)
				)
				(justify left bottom)
				(hide yes)
			)
		)
		(property "Author" "Antmicro"
			(at 105.41 64.77 0)
			(effects
				(font
					(size 1.27 1.27)
					(thickness 0.15)
				)
				(justify left bottom)
				(hide yes)
			)
		)
		(property "License" "Apache-2.0"
			(at 105.41 67.31 0)
			(effects
				(font
					(size 1.27 1.27)
					(thickness 0.15)
				)
				(justify left bottom)
				(hide yes)
			)
		)
		(property "VSD_Class" "USB-C"
			(at 105.41 69.85 0)
			(effects
				(font
					(size 1.27 1.27)
				)
				(justify left bottom)
				(hide yes)
			)
		)
		(pin "A1"
		)
		(pin "A12"
		)
		(pin "A4"
		)
		(pin "A5"
		)
		(pin "A6"
		)
		(pin "A7"
		)
		(pin "A8"
		)
		(pin "A9"
		)
		(pin "B1"
		)
		(pin "B12"
		)
		(pin "B4"
		)
		(pin "B5"
		)
		(pin "B6"
		)
		(pin "B7"
		)
		(pin "B8"
		)
		(pin "B9"
		)
		(pin "SH"
		)
		(instances
			(project "sodimm-ddr5-tester"
				(path ""
					(reference "J3")
					(unit 1)
				)
			)
		)
	)
	(symbol
		(lib_id "antmicroCapacitors0402:C_100n_0402")
		(at 372.237 110.49 90)
		(unit 1)
		(exclude_from_sim no)
		(in_bom yes)
		(on_board yes)
		(dnp no)
		(fields_autoplaced yes)
		(property "Reference" "C124"
			(at 374.5611 107.113 90)
			(effects
				(font
					(size 1.27 1.27)
					(thickness 0.15)
				)
				(justify right)
			)
		)
		(property "Value" "C_100n_0402"
			(at 382.397 90.17 0)
			(effects
				(font
					(size 1.27 1.27)
					(thickness 0.15)
				)
				(justify left bottom)
				(hide yes)
			)
		)
		(property "Footprint" "antmicro-footprints:C_0402_1005Metric"
			(at 384.937 90.17 0)
			(effects
				(font
					(size 1.27 1.27)
					(thickness 0.15)
				)
				(justify left bottom)
				(hide yes)
			)
		)
		(property "Datasheet" "https://www.murata.com/products/productdetail?partno=GRM155R61H104KE14%23"
			(at 387.477 90.17 0)
			(effects
				(font
					(size 1.27 1.27)
					(thickness 0.15)
				)
				(justify left bottom)
				(hide yes)
			)
		)
		(property "Description" ""
			(at 372.237 110.49 0)
			(effects
				(font
					(size 1.27 1.27)
				)
			)
		)
		(property "MPN" "GRM155R61H104KE14D"
			(at 390.017 90.17 0)
			(effects
				(font
					(size 1.27 1.27)
					(thickness 0.15)
				)
				(justify left bottom)
				(hide yes)
			)
		)
		(property "Manufacturer" "Murata"
			(at 392.557 90.17 0)
			(effects
				(font
					(size 1.27 1.27)
					(thickness 0.15)
				)
				(justify left bottom)
				(hide yes)
			)
		)
		(property "License" "Apache-2.0"
			(at 395.097 90.17 0)
			(effects
				(font
					(size 1.27 1.27)
					(thickness 0.15)
				)
				(justify left bottom)
				(hide yes)
			)
		)
		(property "Author" "Antmicro"
			(at 397.637 90.17 0)
			(effects
				(font
					(size 1.27 1.27)
					(thickness 0.15)
				)
				(justify left bottom)
				(hide yes)
			)
		)
		(property "Val" "100n"
			(at 374.5611 109.6367 90)
			(effects
				(font
					(size 1.27 1.27)
					(thickness 0.15)
				)
				(justify right)
			)
		)
		(property "Voltage" "50V"
			(at 400.177 90.17 0)
			(effects
				(font
					(size 1.27 1.27)
				)
				(justify left bottom)
				(hide yes)
			)
		)
		(property "Dielectric" "X5R"
			(at 402.717 90.17 0)
			(effects
				(font
					(size 1.27 1.27)
				)
				(justify left bottom)
				(hide yes)
			)
		)
		(pin "1"
		)
		(pin "2"
		)
		(instances
			(project "sodimm-ddr5-tester"
				(path ""
					(reference "C124")
					(unit 1)
				)
			)
		)
	)
	(symbol
		(lib_id "antmicropower:GND")
		(at 85.725 54.61 90)
		(mirror x)
		(unit 1)
		(exclude_from_sim no)
		(in_bom yes)
		(on_board yes)
		(dnp no)
		(fields_autoplaced yes)
		(property "Reference" "#PWR0352"
			(at 92.075 54.61 0)
			(effects
				(font
					(size 1.27 1.27)
				)
				(hide yes)
			)
		)
		(property "Value" "GND"
			(at 88.9 54.61 90)
			(effects
				(font
					(size 1.27 1.27)
					(thickness 0.15)
				)
				(justify right)
			)
		)
		(property "Footprint" ""
			(at 93.345 63.5 0)
			(effects
				(font
					(size 1.27 1.27)
					(thickness 0.15)
				)
				(justify left bottom)
				(hide yes)
			)
		)
		(property "Datasheet" ""
			(at 98.425 63.5 0)
			(effects
				(font
					(size 1.27 1.27)
					(thickness 0.15)
				)
				(justify left bottom)
				(hide yes)
			)
		)
		(property "Description" ""
			(at 100.965 63.5 0)
			(effects
				(font
					(size 1.27 1.27)
				)
				(justify left bottom)
				(hide yes)
			)
		)
		(property "Author" "Antmicro"
			(at 93.345 63.5 0)
			(effects
				(font
					(size 1.27 1.27)
					(thickness 0.15)
				)
				(justify left bottom)
				(hide yes)
			)
		)
		(property "License" "Apache-2.0"
			(at 95.885 63.5 0)
			(effects
				(font
					(size 1.27 1.27)
					(thickness 0.15)
				)
				(justify left bottom)
				(hide yes)
			)
		)
		(pin "1"
		)
		(instances
			(project "sodimm-ddr5-tester"
				(path ""
					(reference "#PWR0352")
					(unit 1)
				)
			)
		)
	)
	(symbol
		(lib_id "antmicroFerriteBeadsandChips:FB_600Z_0.5A_Murata-BLM18AG_0603")
		(at 51.308 139.065 0)
		(unit 1)
		(exclude_from_sim no)
		(in_bom yes)
		(on_board yes)
		(dnp no)
		(fields_autoplaced yes)
		(property "Reference" "FB2"
			(at 53.8099 133.67 0)
			(effects
				(font
					(size 1.27 1.27)
					(thickness 0.15)
				)
			)
		)
		(property "Value" "FB_600Z_0.5A_Murata-BLM18AG_0603"
			(at 66.548 141.605 0)
			(effects
				(font
					(size 1.27 1.27)
					(thickness 0.15)
				)
				(justify left bottom)
				(hide yes)
			)
		)
		(property "Footprint" "antmicro-footprints:FB_0603_1608Metric"
			(at 66.548 146.685 0)
			(effects
				(font
					(size 1.27 1.27)
					(thickness 0.15)
				)
				(justify left bottom)
				(hide yes)
			)
		)
		(property "Datasheet" "https://www.murata.com/en-us/products/productdata/8796738650142/ENFA0003.pdf"
			(at 66.548 149.225 0)
			(effects
				(font
					(size 1.27 1.27)
					(thickness 0.15)
				)
				(justify left bottom)
				(hide yes)
			)
		)
		(property "Description" ""
			(at 51.308 139.065 0)
			(effects
				(font
					(size 1.27 1.27)
				)
			)
		)
		(property "Val" "600Z/0.5A"
			(at 53.8099 136.2003 0)
			(effects
				(font
					(size 1.27 1.27)
				)
			)
		)
		(property "MPN" "BLM18AG601SN1D"
			(at 66.548 151.765 0)
			(effects
				(font
					(size 1.27 1.27)
					(thickness 0.15)
				)
				(justify left bottom)
				(hide yes)
			)
		)
		(property "Manufacturer" "Murata"
			(at 66.548 154.305 0)
			(effects
				(font
					(size 1.27 1.27)
					(thickness 0.15)
				)
				(justify left bottom)
				(hide yes)
			)
		)
		(property "Author" "Antmicro"
			(at 66.548 156.845 0)
			(effects
				(font
					(size 1.27 1.27)
					(thickness 0.15)
				)
				(justify left bottom)
				(hide yes)
			)
		)
		(property "License" "Apache-2.0"
			(at 66.548 159.385 0)
			(effects
				(font
					(size 1.27 1.27)
					(thickness 0.15)
				)
				(justify left bottom)
				(hide yes)
			)
		)
		(pin "1"
		)
		(pin "2"
		)
		(instances
			(project "sodimm-ddr5-tester"
				(path ""
					(reference "FB2")
					(unit 1)
				)
			)
		)
	)
	(symbol
		(lib_id "antmicroTestPoints:TP_1mm_SMD")
		(at 232.41 275.59 270)
		(unit 1)
		(exclude_from_sim no)
		(in_bom yes)
		(on_board yes)
		(dnp no)
		(property "Reference" "TP44"
			(at 232.41 280.5628 90)
			(effects
				(font
					(size 1.27 1.27)
				)
			)
		)
		(property "Value" "TP_1mm_SMD"
			(at 224.79 290.83 0)
			(effects
				(font
					(size 1.27 1.27)
					(thickness 0.15)
				)
				(justify left bottom)
				(hide yes)
			)
		)
		(property "Footprint" "antmicro-footprints:TP_SMD_1mm"
			(at 222.25 290.83 0)
			(effects
				(font
					(size 1.27 1.27)
					(thickness 0.15)
				)
				(justify left bottom)
				(hide yes)
			)
		)
		(property "Datasheet" ""
			(at 219.71 290.83 0)
			(effects
				(font
					(size 1.27 1.27)
					(thickness 0.15)
				)
				(justify left bottom)
				(hide yes)
			)
		)
		(property "Description" ""
			(at 232.41 275.59 0)
			(effects
				(font
					(size 1.27 1.27)
				)
			)
		)
		(property "MPN" ""
			(at 232.41 275.59 0)
			(effects
				(font
					(size 1.27 1.27)
				)
				(hide yes)
			)
		)
		(property "Manufacturer" ""
			(at 232.41 275.59 0)
			(effects
				(font
					(size 1.27 1.27)
				)
				(hide yes)
			)
		)
		(property "Author" "Antmicro"
			(at 217.17 290.83 0)
			(effects
				(font
					(size 1.27 1.27)
					(thickness 0.15)
				)
				(justify left bottom)
				(hide yes)
			)
		)
		(property "License" "Apache-2.0"
			(at 214.63 290.83 0)
			(effects
				(font
					(size 1.27 1.27)
					(thickness 0.15)
				)
				(justify left bottom)
				(hide yes)
			)
		)
		(pin "1"
		)
		(instances
			(project "sodimm-ddr5-tester"
				(path ""
					(reference "TP44")
					(unit 1)
				)
			)
		)
	)
	(symbol
		(lib_id "antmicropower:GND")
		(at 360.045 194.945 0)
		(unit 1)
		(exclude_from_sim no)
		(in_bom yes)
		(on_board yes)
		(dnp no)
		(property "Reference" "#PWR013"
			(at 360.045 201.295 0)
			(effects
				(font
					(size 1.27 1.27)
				)
				(hide yes)
			)
		)
		(property "Value" "GND"
			(at 358.14 199.39 0)
			(effects
				(font
					(size 1.27 1.27)
					(thickness 0.15)
				)
				(justify left bottom)
			)
		)
		(property "Footprint" ""
			(at 368.935 202.565 0)
			(effects
				(font
					(size 1.27 1.27)
					(thickness 0.15)
				)
				(justify left bottom)
				(hide yes)
			)
		)
		(property "Datasheet" ""
			(at 368.935 207.645 0)
			(effects
				(font
					(size 1.27 1.27)
					(thickness 0.15)
				)
				(justify left bottom)
				(hide yes)
			)
		)
		(property "Description" ""
			(at 368.935 210.185 0)
			(effects
				(font
					(size 1.27 1.27)
				)
				(justify left bottom)
				(hide yes)
			)
		)
		(property "Author" "Antmicro"
			(at 368.935 202.565 0)
			(effects
				(font
					(size 1.27 1.27)
					(thickness 0.15)
				)
				(justify left bottom)
				(hide yes)
			)
		)
		(property "License" "Apache-2.0"
			(at 368.935 205.105 0)
			(effects
				(font
					(size 1.27 1.27)
					(thickness 0.15)
				)
				(justify left bottom)
				(hide yes)
			)
		)
		(pin "1"
		)
		(instances
			(project "sodimm-ddr5-tester"
				(path ""
					(reference "#PWR013")
					(unit 1)
				)
			)
		)
	)
	(symbol
		(lib_id "antmicropower:+3V3")
		(at 372.11 166.37 0)
		(unit 1)
		(exclude_from_sim no)
		(in_bom yes)
		(on_board yes)
		(dnp no)
		(property "Reference" "#PWR014"
			(at 372.11 170.18 0)
			(effects
				(font
					(size 1.27 1.27)
				)
				(hide yes)
			)
		)
		(property "Value" "+3V3"
			(at 368.935 163.83 0)
			(effects
				(font
					(size 1.27 1.27)
					(thickness 0.15)
				)
				(justify left bottom)
			)
		)
		(property "Footprint" ""
			(at 387.35 173.99 0)
			(effects
				(font
					(size 1.27 1.27)
					(thickness 0.15)
				)
				(justify left bottom)
				(hide yes)
			)
		)
		(property "Datasheet" ""
			(at 387.35 176.53 0)
			(effects
				(font
					(size 1.27 1.27)
					(thickness 0.15)
				)
				(justify left bottom)
				(hide yes)
			)
		)
		(property "Description" ""
			(at 372.11 166.37 0)
			(effects
				(font
					(size 1.27 1.27)
				)
			)
		)
		(property "Author" "Antmicro"
			(at 387.35 168.91 0)
			(effects
				(font
					(size 1.27 1.27)
					(thickness 0.15)
				)
				(justify left bottom)
				(hide yes)
			)
		)
		(property "License" "Apache-2.0"
			(at 387.35 171.45 0)
			(effects
				(font
					(size 1.27 1.27)
					(thickness 0.15)
				)
				(justify left bottom)
				(hide yes)
			)
		)
		(pin "1"
		)
		(instances
			(project "sodimm-ddr5-tester"
				(path ""
					(reference "#PWR014")
					(unit 1)
				)
			)
		)
	)
	(symbol
		(lib_id "antmicroResistors0402:R_10k_0402")
		(at 147.32 226.06 90)
		(mirror x)
		(unit 1)
		(exclude_from_sim no)
		(in_bom yes)
		(on_board yes)
		(dnp no)
		(property "Reference" "R79"
			(at 148.59 227.33 90)
			(effects
				(font
					(size 1.27 1.27)
				)
				(justify right)
			)
		)
		(property "Value" "R_10k_0402"
			(at 160.02 246.38 0)
			(effects
				(font
					(size 1.27 1.27)
					(thickness 0.15)
				)
				(justify left bottom)
				(hide yes)
			)
		)
		(property "Footprint" "antmicro-footprints:R_0402_1005Metric"
			(at 162.56 246.38 0)
			(effects
				(font
					(size 1.27 1.27)
					(thickness 0.15)
				)
				(justify left bottom)
				(hide yes)
			)
		)
		(property "Datasheet" "https://www.bourns.com/docs/product-datasheets/cr.pdf"
			(at 165.1 246.38 0)
			(effects
				(font
					(size 1.27 1.27)
					(thickness 0.15)
				)
				(justify left bottom)
				(hide yes)
			)
		)
		(property "Description" ""
			(at 147.32 226.06 0)
			(effects
				(font
					(size 1.27 1.27)
				)
			)
		)
		(property "Manufacturer" "Bourns"
			(at 170.18 246.38 0)
			(effects
				(font
					(size 1.27 1.27)
					(thickness 0.15)
				)
				(justify left bottom)
				(hide yes)
			)
		)
		(property "MPN" "CR0402-FX-1002GLF"
			(at 167.64 246.38 0)
			(effects
				(font
					(size 1.27 1.27)
					(thickness 0.15)
				)
				(justify left bottom)
				(hide yes)
			)
		)
		(property "Val" "10k"
			(at 148.59 229.87 90)
			(effects
				(font
					(size 1.27 1.27)
					(thickness 0.15)
				)
				(justify right)
			)
		)
		(property "License" "Apache-2.0"
			(at 172.72 246.38 0)
			(effects
				(font
					(size 1.27 1.27)
					(thickness 0.15)
				)
				(justify left bottom)
				(hide yes)
			)
		)
		(property "Author" "Antmicro"
			(at 175.26 246.38 0)
			(effects
				(font
					(size 1.27 1.27)
					(thickness 0.15)
				)
				(justify left bottom)
				(hide yes)
			)
		)
		(property "Tolerance" "1%"
			(at 157.48 246.38 0)
			(effects
				(font
					(size 1.27 1.27)
				)
				(justify left bottom)
				(hide yes)
			)
		)
		(pin "1"
		)
		(pin "2"
		)
		(instances
			(project "sodimm-ddr5-tester"
				(path ""
					(reference "R79")
					(unit 1)
				)
			)
		)
	)
	(symbol
		(lib_id "antmicropower:GND")
		(at 156.21 232.41 0)
		(unit 1)
		(exclude_from_sim no)
		(in_bom yes)
		(on_board yes)
		(dnp no)
		(property "Reference" "#PWR0215"
			(at 156.21 238.76 0)
			(effects
				(font
					(size 1.27 1.27)
				)
				(hide yes)
			)
		)
		(property "Value" "GND"
			(at 154.305 236.855 0)
			(effects
				(font
					(size 1.27 1.27)
					(thickness 0.15)
				)
				(justify left bottom)
			)
		)
		(property "Footprint" ""
			(at 165.1 240.03 0)
			(effects
				(font
					(size 1.27 1.27)
					(thickness 0.15)
				)
				(justify left bottom)
				(hide yes)
			)
		)
		(property "Datasheet" ""
			(at 165.1 245.11 0)
			(effects
				(font
					(size 1.27 1.27)
					(thickness 0.15)
				)
				(justify left bottom)
				(hide yes)
			)
		)
		(property "Description" ""
			(at 165.1 247.65 0)
			(effects
				(font
					(size 1.27 1.27)
				)
				(justify left bottom)
				(hide yes)
			)
		)
		(property "Author" "Antmicro"
			(at 165.1 240.03 0)
			(effects
				(font
					(size 1.27 1.27)
					(thickness 0.15)
				)
				(justify left bottom)
				(hide yes)
			)
		)
		(property "License" "Apache-2.0"
			(at 165.1 242.57 0)
			(effects
				(font
					(size 1.27 1.27)
					(thickness 0.15)
				)
				(justify left bottom)
				(hide yes)
			)
		)
		(pin "1"
		)
		(instances
			(project "sodimm-ddr5-tester"
				(path ""
					(reference "#PWR0215")
					(unit 1)
				)
			)
		)
	)
	(symbol
		(lib_id "antmicroResistors0402:R_330R_0402")
		(at 90.17 238.76 0)
		(unit 1)
		(exclude_from_sim no)
		(in_bom yes)
		(on_board yes)
		(dnp no)
		(property "Reference" "R64"
			(at 95.25 238.76 0)
			(effects
				(font
					(size 1.27 1.27)
				)
				(justify left bottom)
			)
		)
		(property "Value" "R_330R_0402"
			(at 110.49 251.46 0)
			(effects
				(font
					(size 1.27 1.27)
					(thickness 0.15)
				)
				(justify left bottom)
				(hide yes)
			)
		)
		(property "Footprint" "antmicro-footprints:R_0402_1005Metric"
			(at 110.49 254 0)
			(effects
				(font
					(size 1.27 1.27)
					(thickness 0.15)
				)
				(justify left bottom)
				(hide yes)
			)
		)
		(property "Datasheet" "https://www.bourns.com/docs/product-datasheets/cr.pdf"
			(at 110.49 256.54 0)
			(effects
				(font
					(size 1.27 1.27)
					(thickness 0.15)
				)
				(justify left bottom)
				(hide yes)
			)
		)
		(property "Description" ""
			(at 90.17 238.76 0)
			(effects
				(font
					(size 1.27 1.27)
				)
			)
		)
		(property "Manufacturer" "Bourns"
			(at 110.49 261.62 0)
			(effects
				(font
					(size 1.27 1.27)
					(thickness 0.15)
				)
				(justify left bottom)
				(hide yes)
			)
		)
		(property "MPN" "CR0402-FX-3300GLF"
			(at 110.49 259.08 0)
			(effects
				(font
					(size 1.27 1.27)
					(thickness 0.15)
				)
				(justify left bottom)
				(hide yes)
			)
		)
		(property "Val" "330R"
			(at 85.09 238.76 0)
			(effects
				(font
					(size 1.27 1.27)
					(thickness 0.15)
				)
				(justify left bottom)
			)
		)
		(property "License" "Apache-2.0"
			(at 110.49 264.16 0)
			(effects
				(font
					(size 1.27 1.27)
					(thickness 0.15)
				)
				(justify left bottom)
				(hide yes)
			)
		)
		(property "Author" "Antmicro"
			(at 110.49 266.7 0)
			(effects
				(font
					(size 1.27 1.27)
					(thickness 0.15)
				)
				(justify left bottom)
				(hide yes)
			)
		)
		(property "Tolerance" "1%"
			(at 110.49 248.92 0)
			(effects
				(font
					(size 1.27 1.27)
				)
				(justify left bottom)
				(hide yes)
			)
		)
		(pin "1"
		)
		(pin "2"
		)
		(instances
			(project "sodimm-ddr5-tester"
				(path ""
					(reference "R64")
					(unit 1)
				)
			)
		)
	)
	(symbol
		(lib_id "antmicropower:GND")
		(at 66.802 147.32 0)
		(unit 1)
		(exclude_from_sim no)
		(in_bom yes)
		(on_board yes)
		(dnp no)
		(fields_autoplaced yes)
		(property "Reference" "#PWR0248"
			(at 66.802 153.67 0)
			(effects
				(font
					(size 1.27 1.27)
				)
				(hide yes)
			)
		)
		(property "Value" "GND"
			(at 69.85 148.59 0)
			(effects
				(font
					(size 1.27 1.27)
					(thickness 0.15)
				)
				(justify left)
			)
		)
		(property "Footprint" ""
			(at 75.692 154.94 0)
			(effects
				(font
					(size 1.27 1.27)
					(thickness 0.15)
				)
				(justify left bottom)
				(hide yes)
			)
		)
		(property "Datasheet" ""
			(at 75.692 160.02 0)
			(effects
				(font
					(size 1.27 1.27)
					(thickness 0.15)
				)
				(justify left bottom)
				(hide yes)
			)
		)
		(property "Description" ""
			(at 75.692 162.56 0)
			(effects
				(font
					(size 1.27 1.27)
				)
				(justify left bottom)
				(hide yes)
			)
		)
		(property "Author" "Antmicro"
			(at 75.692 154.94 0)
			(effects
				(font
					(size 1.27 1.27)
					(thickness 0.15)
				)
				(justify left bottom)
				(hide yes)
			)
		)
		(property "License" "Apache-2.0"
			(at 75.692 157.48 0)
			(effects
				(font
					(size 1.27 1.27)
					(thickness 0.15)
				)
				(justify left bottom)
				(hide yes)
			)
		)
		(pin "1"
		)
		(instances
			(project "sodimm-ddr5-tester"
				(path ""
					(reference "#PWR0248")
					(unit 1)
				)
			)
		)
	)
	(symbol
		(lib_id "antmicroTestPoints:TP_1mm_SMD")
		(at 77.47 46.99 0)
		(mirror x)
		(unit 1)
		(exclude_from_sim no)
		(in_bom yes)
		(on_board yes)
		(dnp no)
		(property "Reference" "TP22"
			(at 81.915 45.085 0)
			(effects
				(font
					(size 1.27 1.27)
				)
			)
		)
		(property "Value" "TP_1mm_SMD"
			(at 92.71 39.37 0)
			(effects
				(font
					(size 1.27 1.27)
					(thickness 0.15)
				)
				(justify left bottom)
				(hide yes)
			)
		)
		(property "Footprint" "antmicro-footprints:TP_SMD_1mm"
			(at 92.71 36.83 0)
			(effects
				(font
					(size 1.27 1.27)
					(thickness 0.15)
				)
				(justify left bottom)
				(hide yes)
			)
		)
		(property "Datasheet" ""
			(at 92.71 34.29 0)
			(effects
				(font
					(size 1.27 1.27)
					(thickness 0.15)
				)
				(justify left bottom)
				(hide yes)
			)
		)
		(property "Description" ""
			(at 77.47 46.99 0)
			(effects
				(font
					(size 1.27 1.27)
				)
			)
		)
		(property "MPN" ""
			(at 77.47 46.99 0)
			(effects
				(font
					(size 1.27 1.27)
				)
				(hide yes)
			)
		)
		(property "Manufacturer" ""
			(at 77.47 46.99 0)
			(effects
				(font
					(size 1.27 1.27)
				)
				(hide yes)
			)
		)
		(property "Author" "Antmicro"
			(at 92.71 31.75 0)
			(effects
				(font
					(size 1.27 1.27)
					(thickness 0.15)
				)
				(justify left bottom)
				(hide yes)
			)
		)
		(property "License" "Apache-2.0"
			(at 92.71 29.21 0)
			(effects
				(font
					(size 1.27 1.27)
					(thickness 0.15)
				)
				(justify left bottom)
				(hide yes)
			)
		)
		(pin "1"
		)
		(instances
			(project "sodimm-ddr5-tester"
				(path ""
					(reference "TP22")
					(unit 1)
				)
			)
		)
	)
	(symbol
		(lib_id "antmicropower:+3V3")
		(at 265.43 191.135 0)
		(unit 1)
		(exclude_from_sim no)
		(in_bom yes)
		(on_board yes)
		(dnp no)
		(property "Reference" "#PWR011"
			(at 265.43 194.945 0)
			(effects
				(font
					(size 1.27 1.27)
				)
				(hide yes)
			)
		)
		(property "Value" "+3V3"
			(at 262.255 188.595 0)
			(effects
				(font
					(size 1.27 1.27)
					(thickness 0.15)
				)
				(justify left bottom)
			)
		)
		(property "Footprint" ""
			(at 280.67 198.755 0)
			(effects
				(font
					(size 1.27 1.27)
					(thickness 0.15)
				)
				(justify left bottom)
				(hide yes)
			)
		)
		(property "Datasheet" ""
			(at 280.67 201.295 0)
			(effects
				(font
					(size 1.27 1.27)
					(thickness 0.15)
				)
				(justify left bottom)
				(hide yes)
			)
		)
		(property "Description" ""
			(at 265.43 191.135 0)
			(effects
				(font
					(size 1.27 1.27)
				)
			)
		)
		(property "Author" "Antmicro"
			(at 280.67 193.675 0)
			(effects
				(font
					(size 1.27 1.27)
					(thickness 0.15)
				)
				(justify left bottom)
				(hide yes)
			)
		)
		(property "License" "Apache-2.0"
			(at 280.67 196.215 0)
			(effects
				(font
					(size 1.27 1.27)
					(thickness 0.15)
				)
				(justify left bottom)
				(hide yes)
			)
		)
		(pin "1"
		)
		(instances
			(project "sodimm-ddr5-tester"
				(path ""
					(reference "#PWR011")
					(unit 1)
				)
			)
		)
	)
	(symbol
		(lib_id "antmicroResistors0402:R_4k7_0402")
		(at 307.34 130.175 270)
		(unit 1)
		(exclude_from_sim no)
		(in_bom yes)
		(on_board yes)
		(dnp no)
		(property "Reference" "R94"
			(at 306.07 131.445 90)
			(effects
				(font
					(size 1.27 1.27)
				)
				(justify right)
			)
		)
		(property "Value" "R_4k7_0402"
			(at 294.64 150.495 0)
			(effects
				(font
					(size 1.27 1.27)
					(thickness 0.15)
				)
				(justify left bottom)
				(hide yes)
			)
		)
		(property "Footprint" "antmicro-footprints:R_0402_1005Metric"
			(at 292.1 150.495 0)
			(effects
				(font
					(size 1.27 1.27)
					(thickness 0.15)
				)
				(justify left bottom)
				(hide yes)
			)
		)
		(property "Datasheet" "https://www.bourns.com/docs/product-datasheets/cr.pdf"
			(at 289.56 150.495 0)
			(effects
				(font
					(size 1.27 1.27)
					(thickness 0.15)
				)
				(justify left bottom)
				(hide yes)
			)
		)
		(property "Description" ""
			(at 307.34 130.175 0)
			(effects
				(font
					(size 1.27 1.27)
				)
			)
		)
		(property "Manufacturer" "Bourns"
			(at 284.48 150.495 0)
			(effects
				(font
					(size 1.27 1.27)
					(thickness 0.15)
				)
				(justify left bottom)
				(hide yes)
			)
		)
		(property "MPN" "CR0402-FX-4701GLF"
			(at 287.02 150.495 0)
			(effects
				(font
					(size 1.27 1.27)
					(thickness 0.15)
				)
				(justify left bottom)
				(hide yes)
			)
		)
		(property "Val" "4k7"
			(at 306.07 134.62 90)
			(effects
				(font
					(size 1.27 1.27)
					(thickness 0.15)
				)
				(justify right)
			)
		)
		(property "License" "Apache-2.0"
			(at 281.94 150.495 0)
			(effects
				(font
					(size 1.27 1.27)
					(thickness 0.15)
				)
				(justify left bottom)
				(hide yes)
			)
		)
		(property "Author" "Antmicro"
			(at 279.4 150.495 0)
			(effects
				(font
					(size 1.27 1.27)
					(thickness 0.15)
				)
				(justify left bottom)
				(hide yes)
			)
		)
		(property "Tolerance" "1%"
			(at 297.18 150.495 0)
			(effects
				(font
					(size 1.27 1.27)
				)
				(justify left bottom)
				(hide yes)
			)
		)
		(pin "1"
		)
		(pin "2"
		)
		(instances
			(project "sodimm-ddr5-tester"
				(path ""
					(reference "R94")
					(unit 1)
				)
			)
		)
	)
	(symbol
		(lib_id "antmicroLogicTranslatorsLevelShifters:TXS0102DQER")
		(at 245.11 168.91 0)
		(unit 1)
		(exclude_from_sim no)
		(in_bom yes)
		(on_board yes)
		(dnp no)
		(fields_autoplaced yes)
		(property "Reference" "U32"
			(at 254 164.465 0)
			(effects
				(font
					(size 1.27 1.27)
					(thickness 0.15)
				)
			)
		)
		(property "Value" "TXS0102DQER"
			(at 254 167.005 0)
			(effects
				(font
					(size 1.27 1.27)
					(thickness 0.15)
				)
			)
		)
		(property "Footprint" "antmicro-footprints:X2SON8_1.4x1x0.32mm_P0.35mm"
			(at 278.13 179.07 0)
			(effects
				(font
					(size 1.27 1.27)
					(thickness 0.15)
				)
				(justify left bottom)
				(hide yes)
			)
		)
		(property "Datasheet" "https://www.ti.com/lit/ds/symlink/txs0102.pdf?ts=1637914596981&ref_url=https%253A%252F%252Fwww.ti.com%252Fstore%252Fti%252Fen%252Fp%252Fproduct%252F%253Fp%253DTXS0102DCTR%2526keyMatch%253DTXS0102DCTR%2526tisearch%253Dsearch-everything%2526usecase%253DOPN"
			(at 278.13 181.61 0)
			(effects
				(font
					(size 1.27 1.27)
					(thickness 0.15)
				)
				(justify left bottom)
				(hide yes)
			)
		)
		(property "Description" ""
			(at 245.11 168.91 0)
			(effects
				(font
					(size 1.27 1.27)
				)
			)
		)
		(property "MPN" "TXS0102DQER"
			(at 278.13 184.15 0)
			(effects
				(font
					(size 1.27 1.27)
					(thickness 0.15)
				)
				(justify left bottom)
				(hide yes)
			)
		)
		(property "Manufacturer" "Texas Instruments"
			(at 278.13 186.69 0)
			(effects
				(font
					(size 1.27 1.27)
					(thickness 0.15)
				)
				(justify left bottom)
				(hide yes)
			)
		)
		(property "Author" "Antmicro"
			(at 278.13 189.23 0)
			(effects
				(font
					(size 1.27 1.27)
					(thickness 0.15)
				)
				(justify left bottom)
				(hide yes)
			)
		)
		(property "License" "Apache-2.0"
			(at 278.13 191.77 0)
			(effects
				(font
					(size 1.27 1.27)
					(thickness 0.15)
				)
				(justify left bottom)
				(hide yes)
			)
		)
		(pin "3"
		)
		(pin "8"
		)
		(pin "7"
		)
		(pin "4"
		)
		(pin "2"
		)
		(pin "1"
		)
		(pin "5"
		)
		(pin "6"
		)
		(instances
			(project "sodimm-ddr5-tester"
				(path ""
					(reference "U32")
					(unit 1)
				)
			)
		)
	)
	(symbol
		(lib_id "antmicropower:GND")
		(at 359.41 135.89 0)
		(unit 1)
		(exclude_from_sim no)
		(in_bom yes)
		(on_board yes)
		(dnp no)
		(property "Reference" "#PWR0200"
			(at 359.41 142.24 0)
			(effects
				(font
					(size 1.27 1.27)
				)
				(hide yes)
			)
		)
		(property "Value" "GND"
			(at 357.505 140.335 0)
			(effects
				(font
					(size 1.27 1.27)
					(thickness 0.15)
				)
				(justify left bottom)
			)
		)
		(property "Footprint" ""
			(at 368.3 143.51 0)
			(effects
				(font
					(size 1.27 1.27)
					(thickness 0.15)
				)
				(justify left bottom)
				(hide yes)
			)
		)
		(property "Datasheet" ""
			(at 368.3 148.59 0)
			(effects
				(font
					(size 1.27 1.27)
					(thickness 0.15)
				)
				(justify left bottom)
				(hide yes)
			)
		)
		(property "Description" ""
			(at 368.3 151.13 0)
			(effects
				(font
					(size 1.27 1.27)
				)
				(justify left bottom)
				(hide yes)
			)
		)
		(property "Author" "Antmicro"
			(at 368.3 143.51 0)
			(effects
				(font
					(size 1.27 1.27)
					(thickness 0.15)
				)
				(justify left bottom)
				(hide yes)
			)
		)
		(property "License" "Apache-2.0"
			(at 368.3 146.05 0)
			(effects
				(font
					(size 1.27 1.27)
					(thickness 0.15)
				)
				(justify left bottom)
				(hide yes)
			)
		)
		(pin "1"
		)
		(instances
			(project "sodimm-ddr5-tester"
				(path ""
					(reference "#PWR0200")
					(unit 1)
				)
			)
		)
	)
	(symbol
		(lib_id "antmicropower:PWR_FLAG")
		(at 65.532 158.115 0)
		(unit 1)
		(exclude_from_sim no)
		(in_bom yes)
		(on_board yes)
		(dnp no)
		(fields_autoplaced yes)
		(property "Reference" "#FLG0102"
			(at 65.532 156.21 0)
			(effects
				(font
					(size 1.27 1.27)
				)
				(hide yes)
			)
		)
		(property "Value" "PWR_FLAG"
			(at 65.532 154.5392 0)
			(effects
				(font
					(size 1.27 1.27)
				)
			)
		)
		(property "Footprint" ""
			(at 65.532 158.115 0)
			(effects
				(font
					(size 1.27 1.27)
				)
				(hide yes)
			)
		)
		(property "Datasheet" ""
			(at 65.532 158.115 0)
			(effects
				(font
					(size 1.27 1.27)
				)
				(hide yes)
			)
		)
		(property "Description" ""
			(at 65.532 158.115 0)
			(effects
				(font
					(size 1.27 1.27)
				)
			)
		)
		(pin "1"
		)
		(instances
			(project "sodimm-ddr5-tester"
				(path ""
					(reference "#FLG0102")
					(unit 1)
				)
			)
		)
	)
	(symbol
		(lib_id "antmicropower:GND")
		(at 122.555 93.345 0)
		(mirror y)
		(unit 1)
		(exclude_from_sim no)
		(in_bom yes)
		(on_board yes)
		(dnp no)
		(property "Reference" "#PWR0230"
			(at 122.555 99.695 0)
			(effects
				(font
					(size 1.27 1.27)
				)
				(hide yes)
			)
		)
		(property "Value" "GND"
			(at 124.46 97.79 0)
			(effects
				(font
					(size 1.27 1.27)
					(thickness 0.15)
				)
				(justify left bottom)
			)
		)
		(property "Footprint" ""
			(at 113.665 100.965 0)
			(effects
				(font
					(size 1.27 1.27)
					(thickness 0.15)
				)
				(justify left bottom)
				(hide yes)
			)
		)
		(property "Datasheet" ""
			(at 113.665 106.045 0)
			(effects
				(font
					(size 1.27 1.27)
					(thickness 0.15)
				)
				(justify left bottom)
				(hide yes)
			)
		)
		(property "Description" ""
			(at 113.665 108.585 0)
			(effects
				(font
					(size 1.27 1.27)
				)
				(justify left bottom)
				(hide yes)
			)
		)
		(property "Author" "Antmicro"
			(at 113.665 100.965 0)
			(effects
				(font
					(size 1.27 1.27)
					(thickness 0.15)
				)
				(justify left bottom)
				(hide yes)
			)
		)
		(property "License" "Apache-2.0"
			(at 113.665 103.505 0)
			(effects
				(font
					(size 1.27 1.27)
					(thickness 0.15)
				)
				(justify left bottom)
				(hide yes)
			)
		)
		(pin "1"
		)
		(instances
			(project "sodimm-ddr5-tester"
				(path ""
					(reference "#PWR0230")
					(unit 1)
				)
			)
		)
	)
	(symbol
		(lib_id "antmicropower:GND")
		(at 371.602 135.89 0)
		(unit 1)
		(exclude_from_sim no)
		(in_bom yes)
		(on_board yes)
		(dnp no)
		(property "Reference" "#PWR0195"
			(at 371.602 142.24 0)
			(effects
				(font
					(size 1.27 1.27)
				)
				(hide yes)
			)
		)
		(property "Value" "GND"
			(at 369.697 140.335 0)
			(effects
				(font
					(size 1.27 1.27)
					(thickness 0.15)
				)
				(justify left bottom)
			)
		)
		(property "Footprint" ""
			(at 380.492 143.51 0)
			(effects
				(font
					(size 1.27 1.27)
					(thickness 0.15)
				)
				(justify left bottom)
				(hide yes)
			)
		)
		(property "Datasheet" ""
			(at 380.492 148.59 0)
			(effects
				(font
					(size 1.27 1.27)
					(thickness 0.15)
				)
				(justify left bottom)
				(hide yes)
			)
		)
		(property "Description" ""
			(at 380.492 151.13 0)
			(effects
				(font
					(size 1.27 1.27)
				)
				(justify left bottom)
				(hide yes)
			)
		)
		(property "Author" "Antmicro"
			(at 380.492 143.51 0)
			(effects
				(font
					(size 1.27 1.27)
					(thickness 0.15)
				)
				(justify left bottom)
				(hide yes)
			)
		)
		(property "License" "Apache-2.0"
			(at 380.492 146.05 0)
			(effects
				(font
					(size 1.27 1.27)
					(thickness 0.15)
				)
				(justify left bottom)
				(hide yes)
			)
		)
		(pin "1"
		)
		(instances
			(project "sodimm-ddr5-tester"
				(path ""
					(reference "#PWR0195")
					(unit 1)
				)
			)
		)
	)
	(symbol
		(lib_id "antmicropower:+3V3")
		(at 372.237 102.87 0)
		(unit 1)
		(exclude_from_sim no)
		(in_bom yes)
		(on_board yes)
		(dnp no)
		(property "Reference" "#PWR0198"
			(at 372.237 106.68 0)
			(effects
				(font
					(size 1.27 1.27)
				)
				(hide yes)
			)
		)
		(property "Value" "+3V3"
			(at 369.062 100.33 0)
			(effects
				(font
					(size 1.27 1.27)
					(thickness 0.15)
				)
				(justify left bottom)
			)
		)
		(property "Footprint" ""
			(at 387.477 110.49 0)
			(effects
				(font
					(size 1.27 1.27)
					(thickness 0.15)
				)
				(justify left bottom)
				(hide yes)
			)
		)
		(property "Datasheet" ""
			(at 387.477 113.03 0)
			(effects
				(font
					(size 1.27 1.27)
					(thickness 0.15)
				)
				(justify left bottom)
				(hide yes)
			)
		)
		(property "Description" ""
			(at 372.237 102.87 0)
			(effects
				(font
					(size 1.27 1.27)
				)
			)
		)
		(property "Author" "Antmicro"
			(at 387.477 105.41 0)
			(effects
				(font
					(size 1.27 1.27)
					(thickness 0.15)
				)
				(justify left bottom)
				(hide yes)
			)
		)
		(property "License" "Apache-2.0"
			(at 387.477 107.95 0)
			(effects
				(font
					(size 1.27 1.27)
					(thickness 0.15)
				)
				(justify left bottom)
				(hide yes)
			)
		)
		(pin "1"
		)
		(instances
			(project "sodimm-ddr5-tester"
				(path ""
					(reference "#PWR0198")
					(unit 1)
				)
			)
		)
	)
	(symbol
		(lib_id "antmicroCapacitors0402:C_100n_0402")
		(at 360.045 193.675 90)
		(unit 1)
		(exclude_from_sim no)
		(in_bom yes)
		(on_board yes)
		(dnp no)
		(fields_autoplaced yes)
		(property "Reference" "C237"
			(at 362.3691 190.298 90)
			(effects
				(font
					(size 1.27 1.27)
					(thickness 0.15)
				)
				(justify right)
			)
		)
		(property "Value" "C_100n_0402"
			(at 370.205 173.355 0)
			(effects
				(font
					(size 1.27 1.27)
					(thickness 0.15)
				)
				(justify left bottom)
				(hide yes)
			)
		)
		(property "Footprint" "antmicro-footprints:C_0402_1005Metric"
			(at 372.745 173.355 0)
			(effects
				(font
					(size 1.27 1.27)
					(thickness 0.15)
				)
				(justify left bottom)
				(hide yes)
			)
		)
		(property "Datasheet" "https://www.murata.com/products/productdetail?partno=GRM155R61H104KE14%23"
			(at 375.285 173.355 0)
			(effects
				(font
					(size 1.27 1.27)
					(thickness 0.15)
				)
				(justify left bottom)
				(hide yes)
			)
		)
		(property "Description" ""
			(at 360.045 193.675 0)
			(effects
				(font
					(size 1.27 1.27)
				)
			)
		)
		(property "MPN" "GRM155R61H104KE14D"
			(at 377.825 173.355 0)
			(effects
				(font
					(size 1.27 1.27)
					(thickness 0.15)
				)
				(justify left bottom)
				(hide yes)
			)
		)
		(property "Manufacturer" "Murata"
			(at 380.365 173.355 0)
			(effects
				(font
					(size 1.27 1.27)
					(thickness 0.15)
				)
				(justify left bottom)
				(hide yes)
			)
		)
		(property "License" "Apache-2.0"
			(at 382.905 173.355 0)
			(effects
				(font
					(size 1.27 1.27)
					(thickness 0.15)
				)
				(justify left bottom)
				(hide yes)
			)
		)
		(property "Author" "Antmicro"
			(at 385.445 173.355 0)
			(effects
				(font
					(size 1.27 1.27)
					(thickness 0.15)
				)
				(justify left bottom)
				(hide yes)
			)
		)
		(property "Val" "100n"
			(at 362.3691 192.8217 90)
			(effects
				(font
					(size 1.27 1.27)
					(thickness 0.15)
				)
				(justify right)
			)
		)
		(property "Voltage" "50V"
			(at 387.985 173.355 0)
			(effects
				(font
					(size 1.27 1.27)
				)
				(justify left bottom)
				(hide yes)
			)
		)
		(property "Dielectric" "X5R"
			(at 390.525 173.355 0)
			(effects
				(font
					(size 1.27 1.27)
				)
				(justify left bottom)
				(hide yes)
			)
		)
		(pin "1"
		)
		(pin "2"
		)
		(instances
			(project "sodimm-ddr5-tester"
				(path ""
					(reference "C237")
					(unit 1)
				)
			)
		)
	)
	(symbol
		(lib_id "antmicroLogicShiftRegisters:SN74HC595B")
		(at 132.08 228.6 0)
		(mirror y)
		(unit 1)
		(exclude_from_sim no)
		(in_bom yes)
		(on_board yes)
		(dnp no)
		(fields_autoplaced yes)
		(property "Reference" "U9"
			(at 121.92 220.345 0)
			(effects
				(font
					(size 1.27 1.27)
				)
			)
		)
		(property "Value" "SN74HC595B"
			(at 121.92 222.885 0)
			(effects
				(font
					(size 1.27 1.27)
					(thickness 0.15)
				)
			)
		)
		(property "Footprint" "antmicro-footprints:X1QFN-16-1EP_2.5x2.5mm"
			(at 96.52 238.76 0)
			(effects
				(font
					(size 1.27 1.27)
					(thickness 0.15)
				)
				(justify left bottom)
				(hide yes)
			)
		)
		(property "Datasheet" "https://www.ti.com/general/docs/suppproductinfo.tsp?distId=26&gotoUrl=https://www.ti.com/lit/gpn/sn74hc595b"
			(at 96.52 241.3 0)
			(effects
				(font
					(size 1.27 1.27)
					(thickness 0.15)
				)
				(justify left bottom)
				(hide yes)
			)
		)
		(property "Description" ""
			(at 132.08 228.6 0)
			(effects
				(font
					(size 1.27 1.27)
				)
			)
		)
		(property "Manufacturer" "Texas Instruments"
			(at 96.52 243.84 0)
			(effects
				(font
					(size 1.27 1.27)
					(thickness 0.15)
				)
				(justify left bottom)
				(hide yes)
			)
		)
		(property "MPN" "SN74HC595BRWNR"
			(at 96.52 246.38 0)
			(effects
				(font
					(size 1.27 1.27)
					(thickness 0.15)
				)
				(justify left bottom)
				(hide yes)
			)
		)
		(property "Author" "Antmicro"
			(at 96.52 248.92 0)
			(effects
				(font
					(size 1.27 1.27)
					(thickness 0.15)
				)
				(justify left bottom)
				(hide yes)
			)
		)
		(property "License" "Apache-2.0"
			(at 96.52 251.46 0)
			(effects
				(font
					(size 1.27 1.27)
					(thickness 0.15)
				)
				(justify left bottom)
				(hide yes)
			)
		)
		(pin "1"
		)
		(pin "10"
		)
		(pin "11"
		)
		(pin "12"
		)
		(pin "13"
		)
		(pin "14"
		)
		(pin "15"
		)
		(pin "16"
		)
		(pin "17"
		)
		(pin "2"
		)
		(pin "3"
		)
		(pin "4"
		)
		(pin "5"
		)
		(pin "6"
		)
		(pin "7"
		)
		(pin "8"
		)
		(pin "9"
		)
		(instances
			(project "sodimm-ddr5-tester"
				(path ""
					(reference "U9")
					(unit 1)
				)
			)
		)
	)
	(symbol
		(lib_id "antmicroResistors0402:R_330R_0402")
		(at 90.17 241.3 0)
		(unit 1)
		(exclude_from_sim no)
		(in_bom yes)
		(on_board yes)
		(dnp no)
		(property "Reference" "R65"
			(at 95.25 241.3 0)
			(effects
				(font
					(size 1.27 1.27)
				)
				(justify left bottom)
			)
		)
		(property "Value" "R_330R_0402"
			(at 110.49 254 0)
			(effects
				(font
					(size 1.27 1.27)
					(thickness 0.15)
				)
				(justify left bottom)
				(hide yes)
			)
		)
		(property "Footprint" "antmicro-footprints:R_0402_1005Metric"
			(at 110.49 256.54 0)
			(effects
				(font
					(size 1.27 1.27)
					(thickness 0.15)
				)
				(justify left bottom)
				(hide yes)
			)
		)
		(property "Datasheet" "https://www.bourns.com/docs/product-datasheets/cr.pdf"
			(at 110.49 259.08 0)
			(effects
				(font
					(size 1.27 1.27)
					(thickness 0.15)
				)
				(justify left bottom)
				(hide yes)
			)
		)
		(property "Description" ""
			(at 90.17 241.3 0)
			(effects
				(font
					(size 1.27 1.27)
				)
			)
		)
		(property "Manufacturer" "Bourns"
			(at 110.49 264.16 0)
			(effects
				(font
					(size 1.27 1.27)
					(thickness 0.15)
				)
				(justify left bottom)
				(hide yes)
			)
		)
		(property "MPN" "CR0402-FX-3300GLF"
			(at 110.49 261.62 0)
			(effects
				(font
					(size 1.27 1.27)
					(thickness 0.15)
				)
				(justify left bottom)
				(hide yes)
			)
		)
		(property "Val" "330R"
			(at 85.09 241.3 0)
			(effects
				(font
					(size 1.27 1.27)
					(thickness 0.15)
				)
				(justify left bottom)
			)
		)
		(property "License" "Apache-2.0"
			(at 110.49 266.7 0)
			(effects
				(font
					(size 1.27 1.27)
					(thickness 0.15)
				)
				(justify left bottom)
				(hide yes)
			)
		)
		(property "Author" "Antmicro"
			(at 110.49 269.24 0)
			(effects
				(font
					(size 1.27 1.27)
					(thickness 0.15)
				)
				(justify left bottom)
				(hide yes)
			)
		)
		(property "Tolerance" "1%"
			(at 110.49 251.46 0)
			(effects
				(font
					(size 1.27 1.27)
				)
				(justify left bottom)
				(hide yes)
			)
		)
		(pin "1"
		)
		(pin "2"
		)
		(instances
			(project "sodimm-ddr5-tester"
				(path ""
					(reference "R65")
					(unit 1)
				)
			)
		)
	)
	(symbol
		(lib_id "antmicroLEDIndicationDiscrete:LED_G_0603_KP-1608CGCK")
		(at 80.645 233.045 180)
		(unit 1)
		(exclude_from_sim no)
		(in_bom yes)
		(on_board yes)
		(dnp no)
		(property "Reference" "D10"
			(at 76.835 230.505 0)
			(effects
				(font
					(size 1.27 1.27)
				)
			)
		)
		(property "Value" "LED_G_0603_KP-1608CGCK"
			(at 54.61 233.045 0)
			(effects
				(font
					(size 1.27 1.27)
					(thickness 0.15)
				)
			)
		)
		(property "Footprint" "antmicro-footprints:LED_0603_1608Metric_G"
			(at 57.785 222.885 0)
			(effects
				(font
					(size 1.27 1.27)
					(thickness 0.15)
				)
				(justify left bottom)
				(hide yes)
			)
		)
		(property "Datasheet" "http://www.farnell.com/datasheets/2045956.pdf"
			(at 57.785 220.345 0)
			(effects
				(font
					(size 1.27 1.27)
					(thickness 0.15)
				)
				(justify left bottom)
				(hide yes)
			)
		)
		(property "Description" ""
			(at 80.645 233.045 0)
			(effects
				(font
					(size 1.27 1.27)
				)
			)
		)
		(property "MPN" "KP-1608CGCK"
			(at 76.2 230.505 0)
			(effects
				(font
					(size 1.27 1.27)
					(thickness 0.15)
				)
				(hide yes)
			)
		)
		(property "Manufacturer" "Kingbright"
			(at 57.785 215.265 0)
			(effects
				(font
					(size 1.27 1.27)
					(thickness 0.15)
				)
				(justify left bottom)
				(hide yes)
			)
		)
		(property "Author" "Antmicro"
			(at 57.785 212.725 0)
			(effects
				(font
					(size 1.27 1.27)
					(thickness 0.15)
				)
				(justify left bottom)
				(hide yes)
			)
		)
		(property "License" "Apache-2.0"
			(at 57.785 210.185 0)
			(effects
				(font
					(size 1.27 1.27)
					(thickness 0.15)
				)
				(justify left bottom)
				(hide yes)
			)
		)
		(pin "1"
		)
		(pin "2"
		)
		(instances
			(project "sodimm-ddr5-tester"
				(path ""
					(reference "D10")
					(unit 1)
				)
			)
		)
	)
	(symbol
		(lib_id "antmicroTestPoints:TP_1mm_SMD")
		(at 281.94 273.05 90)
		(unit 1)
		(exclude_from_sim no)
		(in_bom yes)
		(on_board yes)
		(dnp no)
		(property "Reference" "TP52"
			(at 281.94 268.0772 90)
			(effects
				(font
					(size 1.27 1.27)
				)
			)
		)
		(property "Value" "TP_1mm_SMD"
			(at 289.56 257.81 0)
			(effects
				(font
					(size 1.27 1.27)
					(thickness 0.15)
				)
				(justify left bottom)
				(hide yes)
			)
		)
		(property "Footprint" "antmicro-footprints:TP_SMD_1mm"
			(at 292.1 257.81 0)
			(effects
				(font
					(size 1.27 1.27)
					(thickness 0.15)
				)
				(justify left bottom)
				(hide yes)
			)
		)
		(property "Datasheet" ""
			(at 294.64 257.81 0)
			(effects
				(font
					(size 1.27 1.27)
					(thickness 0.15)
				)
				(justify left bottom)
				(hide yes)
			)
		)
		(property "Description" ""
			(at 281.94 273.05 0)
			(effects
				(font
					(size 1.27 1.27)
				)
			)
		)
		(property "MPN" ""
			(at 281.94 273.05 0)
			(effects
				(font
					(size 1.27 1.27)
				)
				(hide yes)
			)
		)
		(property "Manufacturer" ""
			(at 281.94 273.05 0)
			(effects
				(font
					(size 1.27 1.27)
				)
				(hide yes)
			)
		)
		(property "Author" "Antmicro"
			(at 297.18 257.81 0)
			(effects
				(font
					(size 1.27 1.27)
					(thickness 0.15)
				)
				(justify left bottom)
				(hide yes)
			)
		)
		(property "License" "Apache-2.0"
			(at 299.72 257.81 0)
			(effects
				(font
					(size 1.27 1.27)
					(thickness 0.15)
				)
				(justify left bottom)
				(hide yes)
			)
		)
		(pin "1"
		)
		(instances
			(project "sodimm-ddr5-tester"
				(path ""
					(reference "TP52")
					(unit 1)
				)
			)
		)
	)
	(symbol
		(lib_id "antmicroLEDIndicationDiscrete:LED_G_0603_KP-1608CGCK")
		(at 80.645 252.095 180)
		(unit 1)
		(exclude_from_sim no)
		(in_bom yes)
		(on_board yes)
		(dnp no)
		(property "Reference" "D13"
			(at 76.835 249.555 0)
			(effects
				(font
					(size 1.27 1.27)
				)
			)
		)
		(property "Value" "LED_G_0603_KP-1608CGCK"
			(at 54.61 252.095 0)
			(effects
				(font
					(size 1.27 1.27)
					(thickness 0.15)
				)
			)
		)
		(property "Footprint" "antmicro-footprints:LED_0603_1608Metric_G"
			(at 57.785 241.935 0)
			(effects
				(font
					(size 1.27 1.27)
					(thickness 0.15)
				)
				(justify left bottom)
				(hide yes)
			)
		)
		(property "Datasheet" "http://www.farnell.com/datasheets/2045956.pdf"
			(at 57.785 239.395 0)
			(effects
				(font
					(size 1.27 1.27)
					(thickness 0.15)
				)
				(justify left bottom)
				(hide yes)
			)
		)
		(property "Description" ""
			(at 80.645 252.095 0)
			(effects
				(font
					(size 1.27 1.27)
				)
			)
		)
		(property "MPN" "KP-1608CGCK"
			(at 76.2 249.555 0)
			(effects
				(font
					(size 1.27 1.27)
					(thickness 0.15)
				)
				(hide yes)
			)
		)
		(property "Manufacturer" "Kingbright"
			(at 57.785 234.315 0)
			(effects
				(font
					(size 1.27 1.27)
					(thickness 0.15)
				)
				(justify left bottom)
				(hide yes)
			)
		)
		(property "Author" "Antmicro"
			(at 57.785 231.775 0)
			(effects
				(font
					(size 1.27 1.27)
					(thickness 0.15)
				)
				(justify left bottom)
				(hide yes)
			)
		)
		(property "License" "Apache-2.0"
			(at 57.785 229.235 0)
			(effects
				(font
					(size 1.27 1.27)
					(thickness 0.15)
				)
				(justify left bottom)
				(hide yes)
			)
		)
		(pin "1"
		)
		(pin "2"
		)
		(instances
			(project "sodimm-ddr5-tester"
				(path ""
					(reference "D13")
					(unit 1)
				)
			)
		)
	)
	(symbol
		(lib_id "antmicroFerriteBeadsandChips:FB_600Z_0.5A_Murata-BLM18AG_0603")
		(at 50.673 158.75 0)
		(unit 1)
		(exclude_from_sim no)
		(in_bom yes)
		(on_board yes)
		(dnp no)
		(fields_autoplaced yes)
		(property "Reference" "FB1"
			(at 53.1749 153.355 0)
			(effects
				(font
					(size 1.27 1.27)
					(thickness 0.15)
				)
			)
		)
		(property "Value" "FB_600Z_0.5A_Murata-BLM18AG_0603"
			(at 65.913 161.29 0)
			(effects
				(font
					(size 1.27 1.27)
					(thickness 0.15)
				)
				(justify left bottom)
				(hide yes)
			)
		)
		(property "Footprint" "antmicro-footprints:FB_0603_1608Metric"
			(at 65.913 166.37 0)
			(effects
				(font
					(size 1.27 1.27)
					(thickness 0.15)
				)
				(justify left bottom)
				(hide yes)
			)
		)
		(property "Datasheet" "https://www.murata.com/en-us/products/productdata/8796738650142/ENFA0003.pdf"
			(at 65.913 168.91 0)
			(effects
				(font
					(size 1.27 1.27)
					(thickness 0.15)
				)
				(justify left bottom)
				(hide yes)
			)
		)
		(property "Description" ""
			(at 50.673 158.75 0)
			(effects
				(font
					(size 1.27 1.27)
				)
			)
		)
		(property "Val" "600Z/0.5A"
			(at 53.1749 155.8853 0)
			(effects
				(font
					(size 1.27 1.27)
				)
			)
		)
		(property "MPN" "BLM18AG601SN1D"
			(at 65.913 171.45 0)
			(effects
				(font
					(size 1.27 1.27)
					(thickness 0.15)
				)
				(justify left bottom)
				(hide yes)
			)
		)
		(property "Manufacturer" "Murata"
			(at 65.913 173.99 0)
			(effects
				(font
					(size 1.27 1.27)
					(thickness 0.15)
				)
				(justify left bottom)
				(hide yes)
			)
		)
		(property "Author" "Antmicro"
			(at 65.913 176.53 0)
			(effects
				(font
					(size 1.27 1.27)
					(thickness 0.15)
				)
				(justify left bottom)
				(hide yes)
			)
		)
		(property "License" "Apache-2.0"
			(at 65.913 179.07 0)
			(effects
				(font
					(size 1.27 1.27)
					(thickness 0.15)
				)
				(justify left bottom)
				(hide yes)
			)
		)
		(pin "1"
		)
		(pin "2"
		)
		(instances
			(project "sodimm-ddr5-tester"
				(path ""
					(reference "FB1")
					(unit 1)
				)
			)
		)
	)
	(symbol
		(lib_id "antmicroResistors0402:R_330R_0402")
		(at 90.17 243.84 0)
		(unit 1)
		(exclude_from_sim no)
		(in_bom yes)
		(on_board yes)
		(dnp no)
		(property "Reference" "R66"
			(at 95.25 243.84 0)
			(effects
				(font
					(size 1.27 1.27)
				)
				(justify left bottom)
			)
		)
		(property "Value" "R_330R_0402"
			(at 110.49 256.54 0)
			(effects
				(font
					(size 1.27 1.27)
					(thickness 0.15)
				)
				(justify left bottom)
				(hide yes)
			)
		)
		(property "Footprint" "antmicro-footprints:R_0402_1005Metric"
			(at 110.49 259.08 0)
			(effects
				(font
					(size 1.27 1.27)
					(thickness 0.15)
				)
				(justify left bottom)
				(hide yes)
			)
		)
		(property "Datasheet" "https://www.bourns.com/docs/product-datasheets/cr.pdf"
			(at 110.49 261.62 0)
			(effects
				(font
					(size 1.27 1.27)
					(thickness 0.15)
				)
				(justify left bottom)
				(hide yes)
			)
		)
		(property "Description" ""
			(at 90.17 243.84 0)
			(effects
				(font
					(size 1.27 1.27)
				)
			)
		)
		(property "Manufacturer" "Bourns"
			(at 110.49 266.7 0)
			(effects
				(font
					(size 1.27 1.27)
					(thickness 0.15)
				)
				(justify left bottom)
				(hide yes)
			)
		)
		(property "MPN" "CR0402-FX-3300GLF"
			(at 110.49 264.16 0)
			(effects
				(font
					(size 1.27 1.27)
					(thickness 0.15)
				)
				(justify left bottom)
				(hide yes)
			)
		)
		(property "Val" "330R"
			(at 85.09 243.84 0)
			(effects
				(font
					(size 1.27 1.27)
					(thickness 0.15)
				)
				(justify left bottom)
			)
		)
		(property "License" "Apache-2.0"
			(at 110.49 269.24 0)
			(effects
				(font
					(size 1.27 1.27)
					(thickness 0.15)
				)
				(justify left bottom)
				(hide yes)
			)
		)
		(property "Author" "Antmicro"
			(at 110.49 271.78 0)
			(effects
				(font
					(size 1.27 1.27)
					(thickness 0.15)
				)
				(justify left bottom)
				(hide yes)
			)
		)
		(property "Tolerance" "1%"
			(at 110.49 254 0)
			(effects
				(font
					(size 1.27 1.27)
				)
				(justify left bottom)
				(hide yes)
			)
		)
		(pin "1"
		)
		(pin "2"
		)
		(instances
			(project "sodimm-ddr5-tester"
				(path ""
					(reference "R66")
					(unit 1)
				)
			)
		)
	)
	(symbol
		(lib_id "antmicroTestPoints:TP_1mm_SMD")
		(at 226.06 275.59 270)
		(unit 1)
		(exclude_from_sim no)
		(in_bom yes)
		(on_board yes)
		(dnp no)
		(property "Reference" "TP43"
			(at 226.06 280.5628 90)
			(effects
				(font
					(size 1.27 1.27)
				)
			)
		)
		(property "Value" "TP_1mm_SMD"
			(at 218.44 290.83 0)
			(effects
				(font
					(size 1.27 1.27)
					(thickness 0.15)
				)
				(justify left bottom)
				(hide yes)
			)
		)
		(property "Footprint" "antmicro-footprints:TP_SMD_1mm"
			(at 215.9 290.83 0)
			(effects
				(font
					(size 1.27 1.27)
					(thickness 0.15)
				)
				(justify left bottom)
				(hide yes)
			)
		)
		(property "Datasheet" ""
			(at 213.36 290.83 0)
			(effects
				(font
					(size 1.27 1.27)
					(thickness 0.15)
				)
				(justify left bottom)
				(hide yes)
			)
		)
		(property "Description" ""
			(at 226.06 275.59 0)
			(effects
				(font
					(size 1.27 1.27)
				)
			)
		)
		(property "MPN" ""
			(at 226.06 275.59 0)
			(effects
				(font
					(size 1.27 1.27)
				)
				(hide yes)
			)
		)
		(property "Manufacturer" ""
			(at 226.06 275.59 0)
			(effects
				(font
					(size 1.27 1.27)
				)
				(hide yes)
			)
		)
		(property "Author" "Antmicro"
			(at 210.82 290.83 0)
			(effects
				(font
					(size 1.27 1.27)
					(thickness 0.15)
				)
				(justify left bottom)
				(hide yes)
			)
		)
		(property "License" "Apache-2.0"
			(at 208.28 290.83 0)
			(effects
				(font
					(size 1.27 1.27)
					(thickness 0.15)
				)
				(justify left bottom)
				(hide yes)
			)
		)
		(pin "1"
		)
		(instances
			(project "sodimm-ddr5-tester"
				(path ""
					(reference "TP43")
					(unit 1)
				)
			)
		)
	)
	(symbol
		(lib_id "antmicroCapacitors0402:C_100n_0402")
		(at 359.41 134.62 90)
		(unit 1)
		(exclude_from_sim no)
		(in_bom yes)
		(on_board yes)
		(dnp no)
		(fields_autoplaced yes)
		(property "Reference" "C130"
			(at 361.7341 131.243 90)
			(effects
				(font
					(size 1.27 1.27)
					(thickness 0.15)
				)
				(justify right)
			)
		)
		(property "Value" "C_100n_0402"
			(at 369.57 114.3 0)
			(effects
				(font
					(size 1.27 1.27)
					(thickness 0.15)
				)
				(justify left bottom)
				(hide yes)
			)
		)
		(property "Footprint" "antmicro-footprints:C_0402_1005Metric"
			(at 372.11 114.3 0)
			(effects
				(font
					(size 1.27 1.27)
					(thickness 0.15)
				)
				(justify left bottom)
				(hide yes)
			)
		)
		(property "Datasheet" "https://www.murata.com/products/productdetail?partno=GRM155R61H104KE14%23"
			(at 374.65 114.3 0)
			(effects
				(font
					(size 1.27 1.27)
					(thickness 0.15)
				)
				(justify left bottom)
				(hide yes)
			)
		)
		(property "Description" ""
			(at 359.41 134.62 0)
			(effects
				(font
					(size 1.27 1.27)
				)
			)
		)
		(property "MPN" "GRM155R61H104KE14D"
			(at 377.19 114.3 0)
			(effects
				(font
					(size 1.27 1.27)
					(thickness 0.15)
				)
				(justify left bottom)
				(hide yes)
			)
		)
		(property "Manufacturer" "Murata"
			(at 379.73 114.3 0)
			(effects
				(font
					(size 1.27 1.27)
					(thickness 0.15)
				)
				(justify left bottom)
				(hide yes)
			)
		)
		(property "License" "Apache-2.0"
			(at 382.27 114.3 0)
			(effects
				(font
					(size 1.27 1.27)
					(thickness 0.15)
				)
				(justify left bottom)
				(hide yes)
			)
		)
		(property "Author" "Antmicro"
			(at 384.81 114.3 0)
			(effects
				(font
					(size 1.27 1.27)
					(thickness 0.15)
				)
				(justify left bottom)
				(hide yes)
			)
		)
		(property "Val" "100n"
			(at 361.7341 133.7667 90)
			(effects
				(font
					(size 1.27 1.27)
					(thickness 0.15)
				)
				(justify right)
			)
		)
		(property "Voltage" "50V"
			(at 387.35 114.3 0)
			(effects
				(font
					(size 1.27 1.27)
				)
				(justify left bottom)
				(hide yes)
			)
		)
		(property "Dielectric" "X5R"
			(at 389.89 114.3 0)
			(effects
				(font
					(size 1.27 1.27)
				)
				(justify left bottom)
				(hide yes)
			)
		)
		(pin "1"
		)
		(pin "2"
		)
		(instances
			(project "sodimm-ddr5-tester"
				(path ""
					(reference "C130")
					(unit 1)
				)
			)
		)
	)
	(symbol
		(lib_id "antmicropower:+3V3")
		(at 268.605 97.79 0)
		(unit 1)
		(exclude_from_sim no)
		(in_bom yes)
		(on_board yes)
		(dnp no)
		(property "Reference" "#PWR0192"
			(at 268.605 101.6 0)
			(effects
				(font
					(size 1.27 1.27)
				)
				(hide yes)
			)
		)
		(property "Value" "+3V3"
			(at 265.43 95.25 0)
			(effects
				(font
					(size 1.27 1.27)
					(thickness 0.15)
				)
				(justify left bottom)
			)
		)
		(property "Footprint" ""
			(at 283.845 105.41 0)
			(effects
				(font
					(size 1.27 1.27)
					(thickness 0.15)
				)
				(justify left bottom)
				(hide yes)
			)
		)
		(property "Datasheet" ""
			(at 283.845 107.95 0)
			(effects
				(font
					(size 1.27 1.27)
					(thickness 0.15)
				)
				(justify left bottom)
				(hide yes)
			)
		)
		(property "Description" ""
			(at 268.605 97.79 0)
			(effects
				(font
					(size 1.27 1.27)
				)
			)
		)
		(property "Author" "Antmicro"
			(at 283.845 100.33 0)
			(effects
				(font
					(size 1.27 1.27)
					(thickness 0.15)
				)
				(justify left bottom)
				(hide yes)
			)
		)
		(property "License" "Apache-2.0"
			(at 283.845 102.87 0)
			(effects
				(font
					(size 1.27 1.27)
					(thickness 0.15)
				)
				(justify left bottom)
				(hide yes)
			)
		)
		(pin "1"
		)
		(instances
			(project "sodimm-ddr5-tester"
				(path ""
					(reference "#PWR0192")
					(unit 1)
				)
			)
		)
	)
	(symbol
		(lib_id "antmicropower:GND")
		(at 57.658 167.64 0)
		(unit 1)
		(exclude_from_sim no)
		(in_bom yes)
		(on_board yes)
		(dnp no)
		(fields_autoplaced yes)
		(property "Reference" "#PWR0227"
			(at 57.658 173.99 0)
			(effects
				(font
					(size 1.27 1.27)
				)
				(hide yes)
			)
		)
		(property "Value" "GND"
			(at 59.69 168.91 0)
			(effects
				(font
					(size 1.27 1.27)
					(thickness 0.15)
				)
				(justify left)
			)
		)
		(property "Footprint" ""
			(at 66.548 175.26 0)
			(effects
				(font
					(size 1.27 1.27)
					(thickness 0.15)
				)
				(justify left bottom)
				(hide yes)
			)
		)
		(property "Datasheet" ""
			(at 66.548 180.34 0)
			(effects
				(font
					(size 1.27 1.27)
					(thickness 0.15)
				)
				(justify left bottom)
				(hide yes)
			)
		)
		(property "Description" ""
			(at 66.548 182.88 0)
			(effects
				(font
					(size 1.27 1.27)
				)
				(justify left bottom)
				(hide yes)
			)
		)
		(property "Author" "Antmicro"
			(at 66.548 175.26 0)
			(effects
				(font
					(size 1.27 1.27)
					(thickness 0.15)
				)
				(justify left bottom)
				(hide yes)
			)
		)
		(property "License" "Apache-2.0"
			(at 66.548 177.8 0)
			(effects
				(font
					(size 1.27 1.27)
					(thickness 0.15)
				)
				(justify left bottom)
				(hide yes)
			)
		)
		(pin "1"
		)
		(instances
			(project "sodimm-ddr5-tester"
				(path ""
					(reference "#PWR0227")
					(unit 1)
				)
			)
		)
	)
	(symbol
		(lib_id "antmicroTestPoints:TP_1mm_SMD")
		(at 294.64 275.59 270)
		(unit 1)
		(exclude_from_sim no)
		(in_bom yes)
		(on_board yes)
		(dnp no)
		(property "Reference" "TP54"
			(at 294.64 280.5628 90)
			(effects
				(font
					(size 1.27 1.27)
				)
			)
		)
		(property "Value" "TP_1mm_SMD"
			(at 287.02 290.83 0)
			(effects
				(font
					(size 1.27 1.27)
					(thickness 0.15)
				)
				(justify left bottom)
				(hide yes)
			)
		)
		(property "Footprint" "antmicro-footprints:TP_SMD_1mm"
			(at 284.48 290.83 0)
			(effects
				(font
					(size 1.27 1.27)
					(thickness 0.15)
				)
				(justify left bottom)
				(hide yes)
			)
		)
		(property "Datasheet" ""
			(at 281.94 290.83 0)
			(effects
				(font
					(size 1.27 1.27)
					(thickness 0.15)
				)
				(justify left bottom)
				(hide yes)
			)
		)
		(property "Description" ""
			(at 294.64 275.59 0)
			(effects
				(font
					(size 1.27 1.27)
				)
			)
		)
		(property "MPN" ""
			(at 294.64 275.59 0)
			(effects
				(font
					(size 1.27 1.27)
				)
				(hide yes)
			)
		)
		(property "Manufacturer" ""
			(at 294.64 275.59 0)
			(effects
				(font
					(size 1.27 1.27)
				)
				(hide yes)
			)
		)
		(property "Author" "Antmicro"
			(at 279.4 290.83 0)
			(effects
				(font
					(size 1.27 1.27)
					(thickness 0.15)
				)
				(justify left bottom)
				(hide yes)
			)
		)
		(property "License" "Apache-2.0"
			(at 276.86 290.83 0)
			(effects
				(font
					(size 1.27 1.27)
					(thickness 0.15)
				)
				(justify left bottom)
				(hide yes)
			)
		)
		(pin "1"
		)
		(instances
			(project "sodimm-ddr5-tester"
				(path ""
					(reference "TP54")
					(unit 1)
				)
			)
		)
	)
	(symbol
		(lib_id "antmicropower:GND")
		(at 68.58 254.635 0)
		(unit 1)
		(exclude_from_sim no)
		(in_bom yes)
		(on_board yes)
		(dnp no)
		(property "Reference" "#PWR0223"
			(at 68.58 260.985 0)
			(effects
				(font
					(size 1.27 1.27)
				)
				(hide yes)
			)
		)
		(property "Value" "GND"
			(at 66.675 259.08 0)
			(effects
				(font
					(size 1.27 1.27)
					(thickness 0.15)
				)
				(justify left bottom)
			)
		)
		(property "Footprint" ""
			(at 77.47 262.255 0)
			(effects
				(font
					(size 1.27 1.27)
					(thickness 0.15)
				)
				(justify left bottom)
				(hide yes)
			)
		)
		(property "Datasheet" ""
			(at 77.47 267.335 0)
			(effects
				(font
					(size 1.27 1.27)
					(thickness 0.15)
				)
				(justify left bottom)
				(hide yes)
			)
		)
		(property "Description" ""
			(at 77.47 269.875 0)
			(effects
				(font
					(size 1.27 1.27)
				)
				(justify left bottom)
				(hide yes)
			)
		)
		(property "Author" "Antmicro"
			(at 77.47 262.255 0)
			(effects
				(font
					(size 1.27 1.27)
					(thickness 0.15)
				)
				(justify left bottom)
				(hide yes)
			)
		)
		(property "License" "Apache-2.0"
			(at 77.47 264.795 0)
			(effects
				(font
					(size 1.27 1.27)
					(thickness 0.15)
				)
				(justify left bottom)
				(hide yes)
			)
		)
		(pin "1"
		)
		(instances
			(project "sodimm-ddr5-tester"
				(path ""
					(reference "#PWR0223")
					(unit 1)
				)
			)
		)
	)
	(symbol
		(lib_id "antmicropower:GND")
		(at 65.532 167.64 0)
		(unit 1)
		(exclude_from_sim no)
		(in_bom yes)
		(on_board yes)
		(dnp no)
		(fields_autoplaced yes)
		(property "Reference" "#PWR0247"
			(at 65.532 173.99 0)
			(effects
				(font
					(size 1.27 1.27)
				)
				(hide yes)
			)
		)
		(property "Value" "GND"
			(at 68.58 168.91 0)
			(effects
				(font
					(size 1.27 1.27)
					(thickness 0.15)
				)
				(justify left)
			)
		)
		(property "Footprint" ""
			(at 74.422 175.26 0)
			(effects
				(font
					(size 1.27 1.27)
					(thickness 0.15)
				)
				(justify left bottom)
				(hide yes)
			)
		)
		(property "Datasheet" ""
			(at 74.422 180.34 0)
			(effects
				(font
					(size 1.27 1.27)
					(thickness 0.15)
				)
				(justify left bottom)
				(hide yes)
			)
		)
		(property "Description" ""
			(at 74.422 182.88 0)
			(effects
				(font
					(size 1.27 1.27)
				)
				(justify left bottom)
				(hide yes)
			)
		)
		(property "Author" "Antmicro"
			(at 74.422 175.26 0)
			(effects
				(font
					(size 1.27 1.27)
					(thickness 0.15)
				)
				(justify left bottom)
				(hide yes)
			)
		)
		(property "License" "Apache-2.0"
			(at 74.422 177.8 0)
			(effects
				(font
					(size 1.27 1.27)
					(thickness 0.15)
				)
				(justify left bottom)
				(hide yes)
			)
		)
		(pin "1"
		)
		(instances
			(project "sodimm-ddr5-tester"
				(path ""
					(reference "#PWR0247")
					(unit 1)
				)
			)
		)
	)
	(symbol
		(lib_id "antmicropower:GND")
		(at 264.16 180.34 0)
		(mirror y)
		(unit 1)
		(exclude_from_sim no)
		(in_bom yes)
		(on_board yes)
		(dnp no)
		(property "Reference" "#PWR08"
			(at 264.16 186.69 0)
			(effects
				(font
					(size 1.27 1.27)
				)
				(hide yes)
			)
		)
		(property "Value" "GND"
			(at 266.065 184.785 0)
			(effects
				(font
					(size 1.27 1.27)
					(thickness 0.15)
				)
				(justify left bottom)
			)
		)
		(property "Footprint" ""
			(at 255.27 187.96 0)
			(effects
				(font
					(size 1.27 1.27)
					(thickness 0.15)
				)
				(justify left bottom)
				(hide yes)
			)
		)
		(property "Datasheet" ""
			(at 255.27 193.04 0)
			(effects
				(font
					(size 1.27 1.27)
					(thickness 0.15)
				)
				(justify left bottom)
				(hide yes)
			)
		)
		(property "Description" ""
			(at 255.27 195.58 0)
			(effects
				(font
					(size 1.27 1.27)
				)
				(justify left bottom)
				(hide yes)
			)
		)
		(property "Author" "Antmicro"
			(at 255.27 187.96 0)
			(effects
				(font
					(size 1.27 1.27)
					(thickness 0.15)
				)
				(justify left bottom)
				(hide yes)
			)
		)
		(property "License" "Apache-2.0"
			(at 255.27 190.5 0)
			(effects
				(font
					(size 1.27 1.27)
					(thickness 0.15)
				)
				(justify left bottom)
				(hide yes)
			)
		)
		(pin "1"
		)
		(instances
			(project "sodimm-ddr5-tester"
				(path ""
					(reference "#PWR08")
					(unit 1)
				)
			)
		)
	)
	(symbol
		(lib_id "antmicropower:GND")
		(at 133.35 250.19 0)
		(unit 1)
		(exclude_from_sim no)
		(in_bom yes)
		(on_board yes)
		(dnp no)
		(property "Reference" "#PWR0222"
			(at 133.35 256.54 0)
			(effects
				(font
					(size 1.27 1.27)
				)
				(hide yes)
			)
		)
		(property "Value" "GND"
			(at 131.445 254.635 0)
			(effects
				(font
					(size 1.27 1.27)
					(thickness 0.15)
				)
				(justify left bottom)
			)
		)
		(property "Footprint" ""
			(at 142.24 257.81 0)
			(effects
				(font
					(size 1.27 1.27)
					(thickness 0.15)
				)
				(justify left bottom)
				(hide yes)
			)
		)
		(property "Datasheet" ""
			(at 142.24 262.89 0)
			(effects
				(font
					(size 1.27 1.27)
					(thickness 0.15)
				)
				(justify left bottom)
				(hide yes)
			)
		)
		(property "Description" ""
			(at 142.24 265.43 0)
			(effects
				(font
					(size 1.27 1.27)
				)
				(justify left bottom)
				(hide yes)
			)
		)
		(property "Author" "Antmicro"
			(at 142.24 257.81 0)
			(effects
				(font
					(size 1.27 1.27)
					(thickness 0.15)
				)
				(justify left bottom)
				(hide yes)
			)
		)
		(property "License" "Apache-2.0"
			(at 142.24 260.35 0)
			(effects
				(font
					(size 1.27 1.27)
					(thickness 0.15)
				)
				(justify left bottom)
				(hide yes)
			)
		)
		(pin "1"
		)
		(instances
			(project "sodimm-ddr5-tester"
				(path ""
					(reference "#PWR0222")
					(unit 1)
				)
			)
		)
	)
	(symbol
		(lib_id "antmicroResistors0402:R_22R_0402")
		(at 179.705 138.43 0)
		(unit 1)
		(exclude_from_sim no)
		(in_bom no)
		(on_board yes)
		(dnp yes)
		(property "Reference" "R56"
			(at 186.69 137.16 0)
			(effects
				(font
					(size 1.27 1.27)
				)
			)
		)
		(property "Value" "R_22R_0402"
			(at 200.025 151.13 0)
			(effects
				(font
					(size 1.27 1.27)
					(thickness 0.15)
				)
				(justify left bottom)
				(hide yes)
			)
		)
		(property "Footprint" "antmicro-footprints:R_0402_1005Metric"
			(at 200.025 153.67 0)
			(effects
				(font
					(size 1.27 1.27)
					(thickness 0.15)
				)
				(justify left bottom)
				(hide yes)
			)
		)
		(property "Datasheet" "https://www.bourns.com/docs/product-datasheets/cr.pdf"
			(at 200.025 156.21 0)
			(effects
				(font
					(size 1.27 1.27)
					(thickness 0.15)
				)
				(justify left bottom)
				(hide yes)
			)
		)
		(property "Description" ""
			(at 179.705 138.43 0)
			(effects
				(font
					(size 1.27 1.27)
				)
			)
		)
		(property "Manufacturer" "Bourns"
			(at 200.025 161.29 0)
			(effects
				(font
					(size 1.27 1.27)
					(thickness 0.15)
				)
				(justify left bottom)
				(hide yes)
			)
		)
		(property "MPN" "CR0402-FX-22R0GLF"
			(at 200.025 158.75 0)
			(effects
				(font
					(size 1.27 1.27)
					(thickness 0.15)
				)
				(justify left bottom)
				(hide yes)
			)
		)
		(property "Val" "22R"
			(at 177.8 137.16 0)
			(effects
				(font
					(size 1.27 1.27)
					(thickness 0.15)
				)
			)
		)
		(property "License" "Apache-2.0"
			(at 200.025 163.83 0)
			(effects
				(font
					(size 1.27 1.27)
					(thickness 0.15)
				)
				(justify left bottom)
				(hide yes)
			)
		)
		(property "Author" "Antmicro"
			(at 200.025 166.37 0)
			(effects
				(font
					(size 1.27 1.27)
					(thickness 0.15)
				)
				(justify left bottom)
				(hide yes)
			)
		)
		(property "Tolerance" "1%"
			(at 200.025 148.59 0)
			(effects
				(font
					(size 1.27 1.27)
				)
				(justify left bottom)
				(hide yes)
			)
		)
		(pin "1"
		)
		(pin "2"
		)
		(instances
			(project "sodimm-ddr5-tester"
				(path ""
					(reference "R56")
					(unit 1)
				)
			)
		)
	)
	(symbol
		(lib_id "antmicroResistors0402:R_4k7_0402")
		(at 310.515 130.175 270)
		(unit 1)
		(exclude_from_sim no)
		(in_bom yes)
		(on_board yes)
		(dnp no)
		(property "Reference" "R95"
			(at 311.785 131.445 90)
			(effects
				(font
					(size 1.27 1.27)
				)
				(justify left)
			)
		)
		(property "Value" "R_4k7_0402"
			(at 297.815 150.495 0)
			(effects
				(font
					(size 1.27 1.27)
					(thickness 0.15)
				)
				(justify left bottom)
				(hide yes)
			)
		)
		(property "Footprint" "antmicro-footprints:R_0402_1005Metric"
			(at 295.275 150.495 0)
			(effects
				(font
					(size 1.27 1.27)
					(thickness 0.15)
				)
				(justify left bottom)
				(hide yes)
			)
		)
		(property "Datasheet" "https://www.bourns.com/docs/product-datasheets/cr.pdf"
			(at 292.735 150.495 0)
			(effects
				(font
					(size 1.27 1.27)
					(thickness 0.15)
				)
				(justify left bottom)
				(hide yes)
			)
		)
		(property "Description" ""
			(at 310.515 130.175 0)
			(effects
				(font
					(size 1.27 1.27)
				)
			)
		)
		(property "Manufacturer" "Bourns"
			(at 287.655 150.495 0)
			(effects
				(font
					(size 1.27 1.27)
					(thickness 0.15)
				)
				(justify left bottom)
				(hide yes)
			)
		)
		(property "MPN" "CR0402-FX-4701GLF"
			(at 290.195 150.495 0)
			(effects
				(font
					(size 1.27 1.27)
					(thickness 0.15)
				)
				(justify left bottom)
				(hide yes)
			)
		)
		(property "Val" "4k7"
			(at 311.785 134.62 90)
			(effects
				(font
					(size 1.27 1.27)
					(thickness 0.15)
				)
				(justify left)
			)
		)
		(property "License" "Apache-2.0"
			(at 285.115 150.495 0)
			(effects
				(font
					(size 1.27 1.27)
					(thickness 0.15)
				)
				(justify left bottom)
				(hide yes)
			)
		)
		(property "Author" "Antmicro"
			(at 282.575 150.495 0)
			(effects
				(font
					(size 1.27 1.27)
					(thickness 0.15)
				)
				(justify left bottom)
				(hide yes)
			)
		)
		(property "Tolerance" "1%"
			(at 300.355 150.495 0)
			(effects
				(font
					(size 1.27 1.27)
				)
				(justify left bottom)
				(hide yes)
			)
		)
		(pin "1"
		)
		(pin "2"
		)
		(instances
			(project "sodimm-ddr5-tester"
				(path ""
					(reference "R95")
					(unit 1)
				)
			)
		)
	)
	(symbol
		(lib_id "antmicroInterfaceControllers:FT4232H_VQFN")
		(at 111.76 116.84 0)
		(unit 1)
		(exclude_from_sim no)
		(in_bom yes)
		(on_board yes)
		(dnp no)
		(fields_autoplaced yes)
		(property "Reference" "U6"
			(at 132.08 107.95 0)
			(effects
				(font
					(size 1.27 1.27)
				)
			)
		)
		(property "Value" "FT4232H_VQFN"
			(at 132.08 111.76 0)
			(effects
				(font
					(size 1.27 1.27)
					(thickness 0.15)
				)
			)
		)
		(property "Footprint" "antmicro-footprints:QFN-56-1EP_8x8mm_P0.5mm"
			(at 167.64 124.46 0)
			(effects
				(font
					(size 1.27 1.27)
					(thickness 0.15)
				)
				(justify left bottom)
				(hide yes)
			)
		)
		(property "Datasheet" "https://www.ftdichip.com/Support/Documents/DataSheets/ICs/DS_FT4232H.pdf"
			(at 167.64 127 0)
			(effects
				(font
					(size 1.27 1.27)
					(thickness 0.15)
				)
				(justify left bottom)
				(hide yes)
			)
		)
		(property "Description" ""
			(at 111.76 116.84 0)
			(effects
				(font
					(size 1.27 1.27)
				)
			)
		)
		(property "Manufacturer" "FTDI Chip"
			(at 167.64 129.54 0)
			(effects
				(font
					(size 1.27 1.27)
					(thickness 0.15)
				)
				(justify left bottom)
				(hide yes)
			)
		)
		(property "MPN" "FT4232H-56Q-REEL"
			(at 167.64 132.08 0)
			(effects
				(font
					(size 1.27 1.27)
					(thickness 0.15)
				)
				(justify left bottom)
				(hide yes)
			)
		)
		(property "Author" "Antmicro"
			(at 167.64 134.62 0)
			(effects
				(font
					(size 1.27 1.27)
					(thickness 0.15)
				)
				(justify left bottom)
				(hide yes)
			)
		)
		(property "License" "Apache-2.0"
			(at 167.64 137.16 0)
			(effects
				(font
					(size 1.27 1.27)
					(thickness 0.15)
				)
				(justify left bottom)
				(hide yes)
			)
		)
		(pin "1"
		)
		(pin "10"
		)
		(pin "11"
		)
		(pin "12"
		)
		(pin "13"
		)
		(pin "14"
		)
		(pin "15"
		)
		(pin "16"
		)
		(pin "17"
		)
		(pin "18"
		)
		(pin "19"
		)
		(pin "2"
		)
		(pin "20"
		)
		(pin "21"
		)
		(pin "22"
		)
		(pin "23"
		)
		(pin "24"
		)
		(pin "25"
		)
		(pin "26"
		)
		(pin "27"
		)
		(pin "28"
		)
		(pin "29"
		)
		(pin "3"
		)
		(pin "30"
		)
		(pin "31"
		)
		(pin "32"
		)
		(pin "33"
		)
		(pin "34"
		)
		(pin "35"
		)
		(pin "36"
		)
		(pin "37"
		)
		(pin "38"
		)
		(pin "39"
		)
		(pin "4"
		)
		(pin "40"
		)
		(pin "41"
		)
		(pin "42"
		)
		(pin "43"
		)
		(pin "44"
		)
		(pin "45"
		)
		(pin "46"
		)
		(pin "47"
		)
		(pin "48"
		)
		(pin "49"
		)
		(pin "5"
		)
		(pin "50"
		)
		(pin "51"
		)
		(pin "52"
		)
		(pin "53"
		)
		(pin "54"
		)
		(pin "55"
		)
		(pin "56"
		)
		(pin "57"
		)
		(pin "6"
		)
		(pin "7"
		)
		(pin "8"
		)
		(pin "9"
		)
		(instances
			(project "sodimm-ddr5-tester"
				(path ""
					(reference "U6")
					(unit 1)
				)
			)
		)
	)
	(symbol
		(lib_id "antmicroCapacitors0402:C_100n_0402")
		(at 371.602 134.62 90)
		(unit 1)
		(exclude_from_sim no)
		(in_bom yes)
		(on_board yes)
		(dnp no)
		(fields_autoplaced yes)
		(property "Reference" "C131"
			(at 373.9261 131.243 90)
			(effects
				(font
					(size 1.27 1.27)
					(thickness 0.15)
				)
				(justify right)
			)
		)
		(property "Value" "C_100n_0402"
			(at 381.762 114.3 0)
			(effects
				(font
					(size 1.27 1.27)
					(thickness 0.15)
				)
				(justify left bottom)
				(hide yes)
			)
		)
		(property "Footprint" "antmicro-footprints:C_0402_1005Metric"
			(at 384.302 114.3 0)
			(effects
				(font
					(size 1.27 1.27)
					(thickness 0.15)
				)
				(justify left bottom)
				(hide yes)
			)
		)
		(property "Datasheet" "https://www.murata.com/products/productdetail?partno=GRM155R61H104KE14%23"
			(at 386.842 114.3 0)
			(effects
				(font
					(size 1.27 1.27)
					(thickness 0.15)
				)
				(justify left bottom)
				(hide yes)
			)
		)
		(property "Description" ""
			(at 371.602 134.62 0)
			(effects
				(font
					(size 1.27 1.27)
				)
			)
		)
		(property "MPN" "GRM155R61H104KE14D"
			(at 389.382 114.3 0)
			(effects
				(font
					(size 1.27 1.27)
					(thickness 0.15)
				)
				(justify left bottom)
				(hide yes)
			)
		)
		(property "Manufacturer" "Murata"
			(at 391.922 114.3 0)
			(effects
				(font
					(size 1.27 1.27)
					(thickness 0.15)
				)
				(justify left bottom)
				(hide yes)
			)
		)
		(property "License" "Apache-2.0"
			(at 394.462 114.3 0)
			(effects
				(font
					(size 1.27 1.27)
					(thickness 0.15)
				)
				(justify left bottom)
				(hide yes)
			)
		)
		(property "Author" "Antmicro"
			(at 397.002 114.3 0)
			(effects
				(font
					(size 1.27 1.27)
					(thickness 0.15)
				)
				(justify left bottom)
				(hide yes)
			)
		)
		(property "Val" "100n"
			(at 373.9261 133.7667 90)
			(effects
				(font
					(size 1.27 1.27)
					(thickness 0.15)
				)
				(justify right)
			)
		)
		(property "Voltage" "50V"
			(at 399.542 114.3 0)
			(effects
				(font
					(size 1.27 1.27)
				)
				(justify left bottom)
				(hide yes)
			)
		)
		(property "Dielectric" "X5R"
			(at 402.082 114.3 0)
			(effects
				(font
					(size 1.27 1.27)
				)
				(justify left bottom)
				(hide yes)
			)
		)
		(pin "1"
		)
		(pin "2"
		)
		(instances
			(project "sodimm-ddr5-tester"
				(path ""
					(reference "C131")
					(unit 1)
				)
			)
		)
	)
)
